# HONEY BADGER LSI BASEBOARD GCE(D)-1B BOM of 55.B0710.D11G_20150213.xlsx — HONEY BADGER LSI BASEBOARD GCE( (bom)
| Level | Parent Number | Part Number | Description | Green Factor | Life Cycle State | Manufacturer | Manufacturer Part Number | Source | BOM Usage | M/P Code | S/D | Qty | UoM | Location |
| 1 | 55.B0710.D11G | 022.40001.0541 | SW TACT 4P ST DTS-63N-V ,PA66 | R2_SA; | Released | DIPTRONICS | DTS-63N-V | Single |  | Purchase | DIP | 1 | PCS | SW2 |
| 1 | 55.B0710.D11G | 022.70004.0021 | CAGE ASSY 74548-0211 | R2_SA; | Released | MOLEX | 74548-0211 | Single |  | Purchase | DIP | 1 | PCS | CN4 |
| 1 | 55.B0710.D11G | 06.02907.010 | XTOR MPS2907ARLRAG PNP TO-92 | R2_SA; | Released | ON | MPS2907ARLRAG | Single |  | Purchase | DIP | 1 | PCS | Q4 |
| 1 | 55.B0710.D11G | 06.1BETB.14Z | LED RED/BLUE LTL1BETBEK5H149-WN | R2_SA; | Released | LITEON | LTL1BETBEK5H149-WN | Single |  | Purchase | DIP | 1 | PCS | LED7 |
| 1 | 55.B0710.D11G | 20.50409.164 | CONN EDGE 164P AAA-PCI-006-G05 ,PA46 | R2_SA; | Released | LOTES | AAA-PCI-006-G05 | Single |  | Purchase | DIP | 1 | PCS | CN8 |
| 1 | 55.B0710.D11G | 21.61359.104 | HEAD ML 1R4P ST D2.54 A2541WV0-1QX4PA-6T | R2_SA; | Released | JWT | A2541WV0-1Qx4PA-6T | Single |  | Purchase | DIP | 2 | PCS | SCN5 SCN8 |
| 1 | 55.B0710.D11G | 21.63105.207 | HEAD ML RT 2R14P A2005WR0-2CX7P-6T | R2_SA; | Released | JWT | A2005WR0-2Cx7P-6T | Single |  | Purchase | DIP | 1 | PCS | CN3 |
| 1 | 55.B0710.D11G | 21.65007.102 | HEAD ML 1R2P 68001-202HLF ,PCT | R2_SA; | Released | FCI | 68001-202HLF | Single |  | Purchase | DIP | 1 | PCS | JP1 |
| 1 | 55.B0710.D11G | 22.10254.181 | SKT USB CONN 4P RT 67643-3911 | R2_SA;G_SA; | Released | MOLEX | 67643-3911 | Single |  | Purchase | DIP | 1 | PCS | SKT1 |
| 1 | 55.B0710.D11G | 22.40069.J01 | SW TACT 4P DTS-65R-Q | R2_SA; | Released | DIPTRONICS | DTS-65R-Q | Single |  | Purchase | DIP | 1 | PCS | SW1 |
| 1 | 55.B0710.D11G | 22.70034.181 | HOLDER BTY 2032 AAA-BAT-043-K01 ,PA66 | R2_SA; | Released | LOTES | AAA-BAT-043-K01 | Single |  | Purchase | DIP | 1 | PCS | BAT1 |
| 1 | 55.B0710.D11G | 23.20068.001 | BTY RTC CR2032 KTS | R2_SA;HF_SA; | Released | KTS | BBBCR2032BX | Single |  | Purchase | DIP | 1 | PCS | BAT1 |
| 1 | 55.B0710.D11G | 34.B0701.001 | ASSY HSINK_68X25X30_PUSH PIN_PAD_HB | R2_SA; | Released | CCI | Void | Single |  | Purchase | DIP | 1 | PCS | SU1 |
| 1 | 55.B0710.D11G | 34.B0706.001 | HSINK_31X48X30_PUSH PIN_PAD_HB | R2_SA; | Released | CCI | CCI | Single |  | Purchase | DIP | 1 | PCS | SU2 |
| 1 | 55.B0710.D11G | 42.B0716.001 | SPACER THERMAL H5 HU230H | R2_C; | Released | TBD |  | Single |  | Purchase | DIP | 1 | PCS | Q4 |
| 1 | 55.B0710.D11G | 42.B0717.001 | CVR PANTHER PLUS HB | R2_C; | Released | TBD |  | Single |  | Purchase | DIP | 1 | PCS |  |
| 1 | 55.B0710.D11G | 42.B0719.001 | SPACER 10G CARD LATCH HB GREEN | R2_C; | Released | TBD |  | Single |  | Purchase | DIP | 2 | PCS |  |
| 1 | 55.B0710.D11G | 42.B0720.001 | SPACER 10G CARD HB GREEN | R2_C; | Released | TBD |  | Single |  | Purchase | DIP | 2 | PCS |  |
| 1 | 55.B0710.D11G | 55.B0710.S11G | HONEY BADGER LSI BASEBOARD GCE(S)-1B | N/A; | Released |  |  |  | E | Manufacture | DIP | 1 | PCS |  |
| 2 | 55.B0710.S11G | 074.01278.0A7Z | IC SWAP CTRL ADM1278-2ACPZ-RL LFCSP 32P | R2_SA; | Released | ADI | ADM1278-2ACPZ-RL | Single |  | Purchase | SMT | 1 | PCS | U2 |
| 2 | 55.B0710.S11G | 075.09904.0A7C | IC DIOSE ESD PROT AZC099-04S SOT23-6L | R2_C; | Released | AMAZING | AZC099-04S | Single |  | Purchase | SMT | 1 | PCS | U22 |
| 2 | 55.B0710.S11G | 078.47522.0211 | CHIP CAP C 4.7U 25V K0805 X7R | R2_SA;HF_SA;G_SA; | Released | WALSIN;SAMSUNG;MURATA | 0805B475K250CT;CL21B475KAFNNNE;GRM21BR71E475KA73L | Multiple |  | Purchase | SMT | 3 | PCS | PC184 PC26 PC46 |
| 2 | 55.B0710.S11G | 19-000386$AB | IC CTRL SAS3X24RLC1-DB-500021106 FPBGA | R2_C; | Released | LSI | 500021106 | Single |  | Purchase | SMT | 1 | PCS | SU1 |
| 2 | 55.B0710.S11G | 19-000387$AA | IC CTRL SAS3008C0-1-DB-500020657 FPBGA | R2_C; | Released | LSI | 500020657 | Single |  | Purchase | SMT | 1 | PCS | SU2 |
| 2 | 55.B0710.S11G | 20.F0977.026 | CONN CTR 26P 75586-0009 SMD ,LCP | R2_SA;G_SA; | Released | MOLEX | 75586-0009 | Single |  | Purchase | SMT | 1 | PCS | CN1 |
| 2 | 55.B0710.S11G | 20.F0986.036 | CONN CTR SMD 36P G40MR36U11AEU ,LCP | R2_SA; | Released | AMPHENOL | G40MR36U11AEU | Single |  | Purchase | SMT | 1 | PCS | CN2 |
| 2 | 55.B0710.S11G | 20.F1354.120 | CONN CTR SMD 120P 61082-121402LF ,LCP | R2_SA; | Released | FCI | 61082-121402LF | Single |  | Purchase | SMT | 1 | PCS | MEZCN1 |
| 2 | 55.B0710.S11G | 48.B0733.01B | PCB 13948-1B HONEY BADGER BASEBOARD 8L G | R2_C; | Released | GCE |  | Single |  | Purchase | SMT | 1 | PCS |  |
| 2 | 55.B0710.S11G | 62.10089.021 | SKT SPI CONN ACA-SPI-006-K01 ,LCP | R2_SA;HF_SA; | Released | LOTES | ACA-SPI-006-K01 | Single |  | Purchase | SMT | 1 | PCS | SKT3 |
| 2 | 55.B0710.S11G | 62.40007.231 | SW PUSH 5P PTCFGP2-Q-TR SMD | R2_SA; | Released | DIPTRONICS | PTCFGP2-Q-TR | Single |  | Purchase | SMT | 1 | PCS | SW3 |
| 2 | 55.B0710.S11G | 62.40018.451 | SW SLIDE 3P LSSM12-P-V-TR SMD | R2_SA; | Released | DIPTRONICS | LSSM12-P-V-TR | Single |  | Purchase | SMT | 1 | PCS | SW20 |
| 2 | 55.B0710.S11G | 63.00000.00L | CHIP RES 0 J 1/10W 0603 | R2_SA;HF_SA;G_SA; | Released | TA-I ; RALEC ; YAGEO ; WALSIN | RM06JTN0 ; RTT03000JTP ; RC0603JR-070RL ; WR06X000PTL | Multiple |  | Purchase | SMT | 8 | PCS | PR150 R446 R545 R551 R554 R556 R557 SR807 |
| 2 | 55.B0710.S11G | 63.10034.1DL | CHIP RES 10 J 1/16W 0402 | R2_SA;HF_SA;G_SA; | Released | TA-I ; RALEC ; CYNTEC ; YAGEO;WALSIN | RM04JTN100 ; RTT02100JTH ; RR0510S-100-JN ; RC0402JR-0710RL;WR04X100JTL | Multiple |  | Purchase | SMT | 1 | PCS | R2111 |
| 2 | 55.B0710.S11G | 63.10234.1DL | CHIP RES 1K J 1/16W 0402 | R2_SA;HF_SA;G_SA; | Released | TA-I;RALEC;CYNTEC;YAGEO;WALSIN | RM04JTN102 ; RTT02102JTH ; RR0510S-102-JN ; RC0402JR-071KL;WR04X102JTL | Multiple |  | Purchase | SMT | 10 | PCS | PR171 R2110 R5202 R576 R600 R604 SR1272 SR1276 SR856 SR860 |
| 2 | 55.B0710.S11G | 63.10434.L1L | CHIP RES 100K J 1/16W 0402 13" REEL | R2_SA;HF_SA;G_SA; | Released | YAGEO;RALEC;WALSIN;TAI | RC0402JR-13100KL;RTT02104JH5;WR04X104 JHL;RM04JLN104 | Multiple |  | Purchase | SMT | 3 | PCS | R2117 R2171 R2174 |
| 2 | 55.B0710.S11G | 63.12334.1DL | CHIP RES 12K J 1/16W 0402 | R2_SA;HF_SA;G_SA; | Released | TA-I ; RALEC ; CYNTEC ; YAGEO | RM04JTN123 ; RTT02123JTH ; RR0510S-123-JN ; RC0402JR-0712KL | Multiple |  | Purchase | SMT | 1 | PCS | R700 |
| 2 | 55.B0710.S11G | 63.15133.15L | CHIP RES 150 J 1/10W 0603 | R2_SA;HF_SA;G_SA; | Released | TA-I ; RALEC ; YAGEO | RM06JTN151 ; RTT03151JTP ; RC0603JR-07150RL | Multiple |  | Purchase | SMT | 2 | PCS | R415 R420 |
| 2 | 55.B0710.S11G | 63.15434.1DL | CHIP RES 150K J 1/16W 0402 | R2_SA;HF_SA;G_SA; | Released | TA-I ; RALEC ; CYNTEC;YAGEO | RM04JTN154 ; RTT02154JTH ; RR-0510S-154-JN ; RC0402JR-07150KL | Multiple |  | Purchase | SMT | 1 | PCS | R2103 |
| 2 | 55.B0710.S11G | 63.18232.11L | CHIP RES 1.8K J 1/4W 1206 | R2_SA;HF_SA;G_SA; | Released | RALEC ; TA-I ; YAGEO | RTT06182JTP ; RM12JTN182 ; RC1206JR-071K8L | Multiple |  | Purchase | SMT | 1 | PCS | R659 |
| 2 | 55.B0710.S11G | 63.22234.1DL | CHIP RES 2.2K J 1/16W 0402 | R2_SA;HF_SA;G_SA; | Released | TA-I;RALEC;CYNTEC;YAGEO;WALSIN | RM04JTN222 ; RTT02222JTH ; RR0510S-222-JN ; RC0402JR-072K2L;WR04X222JTL | Multiple |  | Purchase | SMT | 4 | PCS | R264 R266 R421 R486 |
| 2 | 55.B0710.S11G | 63.27234.1DL | CHIP RES 2.7K J 1/16W 0402 | R2_SA;HF_SA;G_SA; | Released | TA-I ; RALEC ; CYNTEC;YAGEO | RM04JTN272 ; RTT02272JTH ; RR-0510S-272-JN ; RC0402JR-072K7L | Multiple |  | Purchase | SMT | 2 | PCS | PR125 PR82 |
| 2 | 55.B0710.S11G | 63.2R233.15L | CHIP RES 2.2 J 1/10W 0603 | R2_SA;HF_SA;G_SA; | Released | TA-I ; RALEC ; YAGEO ; WALSIN | RM06JTN2R2 ; RTT032R2JTP ; RC0603JR-072R2L ; WR06X2R2JTL | Multiple |  | Purchase | SMT | 4 | PCS | PR19 PR39 PR4 PR9008 |
| 2 | 55.B0710.S11G | 63.30234.1DL | CHIP RES 3K J 1/16W 0402(ROHS) | R2_SA;HF_SA;G_SA; | Released | TA-I;RALEC;CYNTEC;YAGEO;WALSIN | RM04JTN302 ; RTT02302JTH ; RR0510S-302-JN ; RC0402JR-073KL;WR04X302JTL | Multiple |  | Purchase | SMT | 2 | PCS | SR650 SR757 |
| 2 | 55.B0710.S11G | 63.33034.1DL | CHIP RES 33 J 1/16W 0402 | R2_SA;HF_SA;G_SA; | Released | TA-I;RALEC;CYNTEC;YAGEO;WALSIN | RM04JTN330 ; RTT02330JTH ; RR0510S-330-JN ; RC0402JR-0733RL;WR04X330JTL | Multiple |  | Purchase | SMT | 5 | PCS | R375 R376 R379 R458 R528 |
| 2 | 55.B0710.S11G | 63.33137.1BL | CHIP RES 330 J 1/2W 1210 | R2_SA;HF_SA;G_SA; | Released | YAGEO | RC1210JR-07330RL | Single |  | Purchase | SMT | 2 | PCS | R543 R5774 |
| 2 | 55.B0710.S11G | 63.47234.1DL | CHIP RES 4.7K J 1/16W 0402 | R2_SA;HF_SA;G_SA; | Released | TA-I;RALEC;CYNTEC;YAGEO;WALSIN | RM04JTN472 ; RTT02472JTH ; RR0510S-472-JN ; RC0402JR-074K7L;WR04X472JTL | Multiple |  | Purchase | SMT | 1 | PCS | R172 |
| 2 | 55.B0710.S11G | 63.82234.1DL | CHIP RES 8.2K J 1/16W 0402 | R2_SA;HF_SA;G_SA; | Released | TA-I;RALEC;CYNTEC;YAGEO;WALSIN | RM04JTN822 ; RTT02822JTH ; RR0510S-822-JN ; RC0402JR-078K2L;WR04X822JTL | Multiple |  | Purchase | SMT | 6 | PCS | R197 R198 R199 R200 R317 R453 |
| 2 | 55.B0710.S11G | 63.R0031.16L | CHIP RES 0 J 1/8W 0805 | R2_SA;HF_SA;G_SA; | Released | TA-I ; RALEC ; YAGEO ; WALSIN | RM10JTN0 ; RTT05000JTP ; RC0805JR-070RL ; WR08X000PTL | Multiple |  | Purchase | SMT | 2 | PCS | PR153 SR870 |
| 2 | 55.B0710.S11G | 63.R0032.11L | CHIP RES 0 J 1/4W 1206 (ROHS) | R2_SA;HF_SA;G_SA; | Released | TA-I ; RALEC ; YAGEO; WALSIN | RM12JTN0 ; RTT06000JTP ; RC1206JR-070RL; WR12X000 PTL | Multiple |  | Purchase | SMT | 7 | PCS | PR120 PR5 PR77 PR78 PR84 PR85 PR9009 |
| 2 | 55.B0710.S11G | 63.R0034.1DL | CHIP RES 0 J 1/16W 0402 | R2_SA;HF_SA;G_SA; | Released | TA-I;RALEC;CYNTEC;YAGEO;WALSIN | RM04JTN0;RTT02000JTH;RR0510X-000-XN;RC0402JR-070RL;WR04X000PTL | Multiple |  | Purchase | SMT | 293 | PCS | PR11 PR117 PR12 PR124 PR126 PR152 PR169 PR172 PR176 PR178 PR192 PR21 PR22 PR36 PR40 PR56 PR58 PR81 PR83 PR88 PR90 PR9000 PR9001 PR9004 PR9006 PR9015 PR9016 PR9020 R125 R148 R149 R150 R151 R152 R153 R154 R155 R156 R157 R158 R1583 R1587 R159 R162 R168 R169 R179 R180 R181 R182 R183 R184 R19 R190 R191 R204 R205 R206 R207 R208 R209 R210 R211 R2114 R212 R213 R214 R215 R2172 R218 R220 R224 R225 R238 R239 R240 R241 R242 R243 R244 R245 R246 R247 R249 R250 R251 R252 R253 R270 R271 R272 R273 R275 R277 R279 R280 R281 R282 R283 R284 R285 R286 R287 R292 R299 R302 R303 R304 R305 R308 R312 R313 R315 R316 R318 R319 R320 R321 R322 R323 R328 R329 R330 R331 R332 R372 R373 R380 R381 R385 R386 R388 R389 R409 R410 R412 R413 R414 R435 R449 R450 R454 R460 R461 R462 R465 R466 R467 R468 R469 R470 R471 R474 R476 R482 R487 R491 R499 R5200 R5201 R523 R526 R530 R537 R538 R539 R540 R541 R558 R562 R564 R565 R566 R568 R570 R572 R574 R575 R579 R582 R583 R584 R587 R588 R593 R596 R601 R605 R607 R608 R609 R612 R613 R614 R618 R625 R656 R658 R670 R671 R672 R674 R679 R683 R685 R686 R691 R7889 R7900 R7901 R7902 R7903 R7904 R7905 R7906 R7907 R7908 R805 R806 SR1261 SR1271 SR1273 SR1277 SR262 SR265 SR297 SR298 SR309 SR310 SR311 SR581 SR588 SR597 SR656 SR718 SR722 SR723 SR727 SR728 SR729 SR730 SR764 SR788 SR790 SR792 SR793 SR848 SR850 SR858 SR859 SR861 SR862 SR863 SR864 SR865 SR866 SR867 SR871 SR872 SR875 SR876 SR879 SR880 SR883 SR884 SR887 SR888 SR891 SR892 SR894 SR895 SR898 SR899 SR914 SR922 SR923 SR924 SR925 SR926 SR927 SR928 SR929 SR933 SR934 SR935 SR936 SR937 SR938 SR939 SR940 SR941 SR942 SR957 |
| 2 | 55.B0710.S11G | 64.10005.6DL | CHIP RES 100 F 1/16W 0402 | R2_SA;HF_SA;G_SA; | Released | TA-I ; RALEC ; CYNTEC ; YAGEO;WALSIN | RM04FTN1000 ; RTT021000FTH ; RR0510S-1000-FN ; RC0402FR-07100RL;WR04X1000FTL | Multiple |  | Purchase | SMT | 3 | PCS | R15 R16 R20 |
| 2 | 55.B0710.S11G | 64.10015.6DL | CHIP RES 1K F 1/16W 0402 | R2_SA;HF_SA;G_SA; | Released | TA-I;RALEC;CYNTEC;YAGEO;WALSIN | RM04FTN1001 ; RTT021001FTH ; RR0510S-102-FN ; RC0402FR-071KL;WR04X1001FTL | Multiple |  | Purchase | SMT | 23 | PCS | PR118 PR177 R231 R232 R3029 R433 R484 R485 R500 R501 R524 R532 R544 R5763 R5766 R5768 R5769 R5770 R5771 R5772 R675 R676 SR820 |
| 2 | 55.B0710.S11G | 64.10025.55L | CHIP RES 10K F 1/10W 0603 | R2_SA;HF_SA;G_SA; | Released | TA-I ; RALEC ; YAGEO | RM06FTN1002 ; RTT031002FTP ; RC0603FR-0710KL | Multiple |  | Purchase | SMT | 1 | PCS | R690 |
| 2 | 55.B0710.S11G | 64.10025.6DL | CHIP RES 10K F 1/16W 0402 | R2_SA;HF_SA;G_SA; | Released | TA-I;RALEC;CYNTEC;YAGEO;WALSIN | RM04FTN1002 ; RTT021002FTH ; RR0510S-103-FN ; RC0402FR-0710KL;WR04X1002FTL | Multiple |  | Purchase | SMT | 107 | PCS | PR119 PR13 PR165 PR179 PR184 PR186 PR25 PR37 PR45 PR57 PR6 PR9010 PR9017 R1578 R1584 R21 R219 R22 R221 R257 R260 R261 R262 R263 R268 R269 R301 R306 R307 R309 R310 R324 R335 R399 R400 R407 R424 R426 R428 R430 R440 R441 R443 R447 R448 R472 R475 R480 R492 R519 R521 R525 R546 R563 R573 R577 R622 R624 R627 SR1275 SR1280 SR583 SR584 SR605 SR642 SR649 SR653 SR657 SR659 SR661 SR666 SR667 SR668 SR669 SR681 SR682 SR683 SR684 SR685 SR686 SR687 SR689 SR690 SR691 SR692 SR693 SR694 SR696 SR697 SR699 SR700 SR701 SR702 SR703 SR704 SR705 SR706 SR708 SR732 SR784 SR785 SR794 SR840 SR841 SR855 SR915 SR931 |
| 2 | 55.B0710.S11G | 64.10035.6DL | CHIP RES 100K F 1/16W 0402 | R2_SA;HF_SA;G_SA; | Released | TA-I;RALEC;CYNTEC;YAGEO;WALSIN | RM04FTN1003 ; RTT021003FTH ; RR0510S-104-FN ; RC0402FR-07100KL;WR04X1003FTL | Multiple |  | Purchase | SMT | 15 | PCS | PR168 PR170 PR187 R1227 R170 R171 R230 R233 R234 R235 R236 R237 R258 R259 R327 |
| 2 | 55.B0710.S11G | 64.10045.6DL | CHIP RES 1M F 1/16W 0402 | R2_SA;HF_SA;G_SA; | Released | TA-I;RALEC;CYNTEC;YAGEO;WALSIN | RM04FTN1004;RTT021004FTH;RR0510S-105-FN;RC0402FR-071ML;WR04X1004FTL | Multiple |  | Purchase | SMT | 1 | PCS | R701 |
| 2 | 55.B0710.S11G | 64.10R05.55L | CHIP RES 10 F 1/10W 0603 | R2_SA;HF_SA;G_SA; | Released | TA-I;RALEC;YAGEO;WALSIN | RM06FTN10R0 ; RTT0310R0FTP ; RC0603FR-0710RL;WR06X10R0FTL | Multiple |  | Purchase | SMT | 4 | PCS | PR27 PR47 PR9 PR9013 |
| 2 | 55.B0710.S11G | 64.10R05.6DL | CHIP RES 10 F 1/16W 0402 | R2_SA;HF_SA;G_SA; | Released | TA-I ; RALEC ; CYNTEC ; YAGEO | RM04FTN10R0 ; RTT0210R0FTH ; RR0510S-100-FN ; RC0402FR-0710RL | Multiple |  | Purchase | SMT | 16 | PCS | R2098 R2119 R2122 R298 R522 SR709 SR710 SR711 SR712 SR713 SR714 SR828 SR829 SR830 SR837 SR838 |
| 2 | 55.B0710.S11G | 64.10R75.6DL | CHIP RES 10.7 F 1/16W 0402 | R2_SA;HF_SA;G_SA; | Released | TA-I;RALEC;CYNTEC;YAGEO | RM04FTN10R7 ; RTT0210R7FTH ; RR0510S-10R7-FN ; RC0402FR-0710R7L | Multiple |  | Purchase | SMT | 1 | PCS | PR156 |
| 2 | 55.B0710.S11G | 64.11025.6DL | CHIP RES 11K F 1/16W 0402 | R2_SA;HF_SA;G_SA; | Released | TA-I ; RALEC ; CYNTEC ; YAGEO;WALSIN | RM04FTN1102 ; RTT021102FTH ; RR0510S-1102-FN ; RC0402FR-0711KL;WR04X1102FTL | Multiple |  | Purchase | SMT | 1 | PCS | R1226 |
| 2 | 55.B0710.S11G | 64.11335.6DL | CHIP RES 113K F 1/16W 0402 | R2_SA;HF_SA;G_SA; | Released | TAI;RALEC;CYNTEC;YAGEO;WALSIN | RM04FTN1133;RTT021133FTH;RR0510S-1133-FN;RC0402FR-07113KL;WR04X1133FTL | Multiple |  | Purchase | SMT | 1 | PCS | PR164 |
| 2 | 55.B0710.S11G | 64.12115.6DL | CHIP RES 1.21K F 1/16W 0402 | R2_SA;HF_SA;G_SA; | Released | TA-I;RALEC;CYNTEC;YAGEO;WALSIN | RM04FTN1211;RTT021211FTH;RR0510S-1211-FN;RC0402FR-071K21L;WR04X1211FTL | Multiple |  | Purchase | SMT | 1 | PCS | PR183 |
| 2 | 55.B0710.S11G | 64.1271D.6DL | CHIP RES 1.27K D 1/16W 0402 | R2_SA;HF_SA;G_SA; | Released | RALEC ; CYNTEC ; TA-I ; YAGEO | RTT021271DTH ; RR0510Q-1271-DN ; RM04DTN1271 ; RC0402DR-071K27L | Multiple |  | Purchase | SMT | 1 | PCS | R382 |
| 2 | 55.B0710.S11G | 64.13315.55L | CHIP RES 1.33K F 1/10W 0603 | R2_SA;HF_SA;G_SA; | Released | TA-I ; RALEC ; YAGEO | RM06FTN1331 ; RTT031331FTP ; RC0603FR-071K33L | Multiple |  | Purchase | SMT | 2 | PCS | R527 R692 |
| 2 | 55.B0710.S11G | 64.15005.6DL | CHIP RES 150 F 1/16W 0402 | R2_SA;HF_SA;G_SA; | Released | TAI;RALEC;CYNTEC;YAGEO;WALSIN | RM04FTN1500 ; RTT021500FTH ; RR0510S-1500-FN ; RC0402FR-07150RL;WR04X1500FTL | Multiple |  | Purchase | SMT | 9 | PCS | R378 R395 R396 R85 R86 SR651 SR652 SR707 SR731 |
| 2 | 55.B0710.S11G | 64.15025.6DL | CHIP RES 15K F 1/16W 0402 | R2_SA;HF_SA;G_SA; | Released | TA-I;RALEC;CYNTEC;YAGEO | RM04FTN1502;RTT021502FTH;RR0510S-153-FN;RC0402FR-0715KL | Multiple |  | Purchase | SMT | 1 | PCS | R408 |
| 2 | 55.B0710.S11G | 64.18015.6DL | CHIP RES 1.8K F 1/16W 0402 | R2_SA;HF_SA;G_SA; | Released | TAI;RALEC;CYNTEC;YAGEO | RM04FTN1801;RTT021801FTH;RR0510S-182-FN ;RC0402FR-071K8L | Multiple |  | Purchase | SMT | 1 | PCS | R5765 |
| 2 | 55.B0710.S11G | 64.18735.6DL | CHIP RES 187K F 1/16W 0402 | R2_SA;HF_SA;G_SA; | Released | TA-I ; RALEC ; CYNTEC ; YAGEO ; WALSIN | RM04FTN1873;RTT021873FTH;RR0510S-1873-FN;RC0402FR-07187KL;WR04X1873FTL | Multiple |  | Purchase | SMT | 1 | PCS | PR162 |
| 2 | 55.B0710.S11G | 64.19125.6DL | CHIP RES 19.1K F 1/16W 0402 | R2_SA;HF_SA;G_SA; | Released | TA-I;RALEC;CYNTEC;YAGEO | RM04FTN1912;RTT021912FTH;RR0510S-1912-FN;RC0402FR-0719K1L | Multiple |  | Purchase | SMT | 1 | PCS | PR181 |
| 2 | 55.B0710.S11G | 64.20005.55L | CHIP RES 200 F 1/10W 0603(ROHS | R2_SA;HF_SA;G_SA; | Released | TAI;RALEC;YAGEO | RM06FTN2000;RTT032000FTP;RC0603FR-07200RL | Multiple |  | Purchase | SMT | 2 | PCS | R481 R497 |
| 2 | 55.B0710.S11G | 64.20025.6DL | CHIP RES 20K F 1/16W 0402 | R2_SA;HF_SA;G_SA; | Released | TA-I;RALEC;CYNTEC;YAGEO;WALSIN | RM04FTN2002 ; RTT022002FTH ; RR0510S-203-FN ; RC0402FR-0720KL;WR04X2002FTL | Multiple |  | Purchase | SMT | 3 | PCS | PR116 PR175 PR53 |
| 2 | 55.B0710.S11G | 64.20035.6DL | CHIP RES 200K F 1/16W 0402 | R2_SA;HF_SA;G_SA; | Released | TA-I;RALEC;CYNTEC;YAGEO;WALSIN | RM04FTN2003 ; RTT022003FTH ; RR0510S-204-FN ; RC0402FR-07200KL;WR04X2003FTL | Multiple |  | Purchase | SMT | 7 | PCS | SR580 SR724 SR751 SR754 SR761 SR842 SR919 |
| 2 | 55.B0710.S11G | 64.20045.6DL | CHIP RES 2M F 1/16W 0402 | R2_SA;HF_SA;G_SA; | Released | TA-I;RALEC;CYNTEC;YAGEO | RM04FTN2004;RTT022004FTH;RR0510S-2004-FN;RC0402FR-072ML | Multiple |  | Purchase | SMT | 2 | PCS | R478 R494 |
| 2 | 55.B0710.S11G | 64.20515.6DL | CHIP RES 2.05K F 1/16W 0402 | R2_SA;HF_SA;G_SA; | Released | TA-I;RALEC;CYNTEC;YAGEO | RM04FTN2051;RTT022051FTH;RR0510S-2051-FN;RC0402FR-072K05L | Multiple |  | Purchase | SMT | 1 | PCS | PR6889 |
| 2 | 55.B0710.S11G | 64.22005.6DL | CHIP RES 220 F 1/16W 0402 | R2_SA;HF_SA;G_SA; | Released | TA-I;RALEC;CYNTEC;YAGEO | RM04FTN2200;RTT022200FTH;RR0510S-2200-FN;RC0402FR-07220RL | Multiple |  | Purchase | SMT | 1 | PCS | R531 |
| 2 | 55.B0710.S11G | 64.22015.6DL | CHIP RES 2.2K F 1/16W 0402 | R2_SA;HF_SA;G_SA; | Released | TA-I;RALEC;CYNTEC;YAGEO | RM04FTN2201;RTT022201FTH;RR0510S-222-FN;RC0402FR-072K2L | Multiple |  | Purchase | SMT | 30 | PCS | SR614 SR615 SR616 SR617 SR618 SR619 SR620 SR621 SR622 SR623 SR624 SR625 SR626 SR627 SR628 SR629 SR630 SR631 SR632 SR633 SR735 SR736 SR737 SR738 SR739 SR740 SR741 SR742 SR743 SR744 |
| 2 | 55.B0710.S11G | 64.22025.6DL | CHIP RES 22K F 1/16W 0402 | R2_SA;HF_SA;G_SA; | Released | TAI;RALEC;CYNTEC;YAGEO;WALSIN | RM04FTN2202 ; RTT022202FTH ; RR0510S-223-FN ; RC0402FR-0722KL;WR04X2202FTL | Multiple |  | Purchase | SMT | 1 | PCS | R473 |
| 2 | 55.B0710.S11G | 64.22105.6DL | CHIP RES 221 F 1/16W 0402 | R2_SA;HF_SA;G_SA; | Released | TA-I;RALEC;CYNTEC;YAGEO | RM04FTN2210;RTT022210FTH;RR0510S-2210-FN;RC0402FR-07221RL | Multiple |  | Purchase | SMT | 2 | PCS | PR182 PR191 |
| 2 | 55.B0710.S11G | 64.22115.6DL | CHIP RES 2.21K F 1/16W 0402 | R2_SA;HF_SA;G_SA; | Released | TA-I ; RALEC ; CYNTEC ; YAGEO | RM04FTN2211 ; RTT022211FTH ; RR0510S-2211-FN ; RC0402FR-072K21L | Multiple |  | Purchase | SMT | 1 | PCS | PR155 |
| 2 | 55.B0710.S11G | 64.24005.6DL | CHIP RES 240 F 1/16W 0402(ROHS | R2_SA;HF_SA;G_SA; | Released | TA-I ; RALEC ; CYNTEC ; YAGEO | RM04FTN2400 ; RTT022400FTH ; RR0510S-241-FN ; RC0402FR-07240RL | Multiple |  | Purchase | SMT | 1 | PCS | R229 |
| 2 | 55.B0710.S11G | 64.26125.6DL | CHIP RES 26.1K F 1/16W 0402 | R2_SA;HF_SA;G_SA; | Released | TAI;RALEC;CYNTEC;YAGEO | RM04FTN2612;RTT022612FTH;RR0510S-2612-FN;RC0402FR-0726K1L | Multiple |  | Purchase | SMT | 1 | PCS | R2102 |
| 2 | 55.B0710.S11G | 64.27025.6DL | CHIP RES 27K F 1/16W 0402 | R2_SA;HF_SA;G_SA; | Released | TA-I ; RALEC ; CYNTEC ; YAGEO | RM04FTN2702 ; RTT022702FTH ; RR0510S-273-FN ; RC0402FR-0727KL | Multiple |  | Purchase | SMT | 2 | PCS | R518 R626 |
| 2 | 55.B0710.S11G | 64.27415.55L | CHIP RES 2.74K F 1/10W 0603 | R2_SA;HF_SA;G_SA; | Released | TA-I ; RALEC ; YAGEO | RM06FTN2741 ; RTT032741FTP ; RC0603FR-072K74L | Multiple |  | Purchase | SMT | 1 | PCS | R338 |
| 2 | 55.B0710.S11G | 64.27415.6DL | CHIP RES 2.74K F 1/16W 0402 | R2_SA;HF_SA;G_SA; | Released | TAI;RALEC;CYNTEC;YAGEO | RM04FTN2741;RTT022741FTH;RR0510S-2741-FN;RC0402FR-072K74L | Multiple |  | Purchase | SMT | 1 | PCS | PR86 |
| 2 | 55.B0710.S11G | 64.28705.6DL | CHIP RES 287 F 1/16W 0402 | R2_SA;HF_SA;G_SA; | Released | TA-I;RALEC;CYNTEC;YAGEO | RM04FTN2870;RTT022870FTH;RR0510S-2870-FN;RC0402FR-07287RL | Multiple |  | Purchase | SMT | 1 | PCS | PR194 |
| 2 | 55.B0710.S11G | 64.30005.55L | CHIP RES 300 F 1/10W 0603 | R2_SA;HF_SA;G_SA; | Released | TA-I;RALEC;YAGEO;WALSIN | RM06FTN3000;RTT033000FTP;RC0603FR-07300RL;WR06X3000FTL | Multiple |  | Purchase | SMT | 1 | PCS | R673 |
| 2 | 55.B0710.S11G | 64.33015.6DL | CHIP RES 3.3K F 1/16W 0402 | R2_SA;HF_SA;G_SA; | Released | TAI;RALEC;CYNTEC;YAGEO | RM04FTN3301;RTT023301FTH;RR0510S-332-FN;RC0402FR-073K3L | Multiple |  | Purchase | SMT | 9 | PCS | R339 R343 R346 R348 R349 R353 R356 R364 R434 |
| 2 | 55.B0710.S11G | 64.33R05.6DL | CHIP RES 33 F 1/16W 0402 | R2_SA;HF_SA;G_SA; | Released | TA-I;RALEC;CYNTEC;YAGEO;WALSIN | RM04FTN33R0;RTT0233R0FTH;RR0510S-330-FN;RC0402FR-0733RL;WR04X33R0FTL | Multiple |  | Purchase | SMT | 4 | PCS | R1580 R1581 R1582 R1586 |
| 2 | 55.B0710.S11G | 64.34025.6DL | CHIP RES 34K F 1/16W 0402 | R2_SA;HF_SA;G_SA; | Released | TA-I ; RALEC ; CYNTEC ; YAGEO | RM04FTN3402 ; RTT023402FTH ; RR0510S-3402-FN ; RC0402FR-0734KL | Multiple |  | Purchase | SMT | 1 | PCS | SR774 |
| 2 | 55.B0710.S11G | 64.37415.6DL | CHIP RES 3.74K F 1/16W 0402 | R2_SA;HF_SA;G_SA; | Released | TA-I ; RALEC ; CYNTEC ; YAGEO ; WALSIN | RM04FTN3741;RTT023741FTH;RR0510S-3741-FN;RC0402FR-073K74L;WR04X3741FTL | Multiple |  | Purchase | SMT | 1 | PCS | R2108 |
| 2 | 55.B0710.S11G | 64.39015.6DL | CHIP RES 3.9K F 1/16W 0402 | R2_SA;HF_SA;G_SA; | Released | TA-I;RALEC;CYNTEC;YAGEO;WALSIN | RM04FTN3901;RTT023901FTH;RR0510S-3901-FN;RC0402FR-073K9L;WR04X3901FTL | Multiple |  | Purchase | SMT | 2 | PCS | PR26 PR46 |
| 2 | 55.B0710.S11G | 64.39225.6DL | CHIP RES 39.2K F 1/16W 0402 | R2_SA;HF_SA;G_SA; | Released | TA-I;RALEC;CYNTEC;YAGEO;WALSIN | RM04FTN3922 ; RTT023922FTH ; RR0510S-3922-FN ; RC0402FR-0739K2L;WR04X3922FTL | Multiple |  | Purchase | SMT | 1 | PCS | R2099 |
| 2 | 55.B0710.S11G | 64.3R015.16L | CHIP RES 3.01 F 1/8W 0805 | R2_SA;HF_SA;G_SA; | Released | TA-I;RALEC | RM10FTN3R01;RTT053R01FTP | Multiple |  | Purchase | SMT | 2 | PCS | PR20 PR41 |
| 2 | 55.B0710.S11G | 64.40215.6DL | CHIP RES 4.02K F 1/16W 0402 | R2_SA;HF_SA;G_SA; | Released | TA-I;RALEC;CYNTEC;YAGEO;WALSIN | RM04FTN4021;RTT024021FTH;RR0510S-4021-FN;RC0402FR-074K02L;WR04X4021FTL | Multiple |  | Purchase | SMT | 3 | PCS | PR115 PR167 PR173 |
| 2 | 55.B0710.S11G | 64.42215.6DL | CHIP RES 4.22K F 1/16W 0402 | R2_SA;HF_SA;G_SA; | Released | YAGEO;TA-I;CYNTEC;RALEC | RC0402FR-074K22L;RM04FTN4221;RR0510S-4221-FN;RTT024221FTH | Multiple |  | Purchase | SMT | 1 | PCS | PR122 |
| 2 | 55.B0710.S11G | 64.42225.6DL | CHIP RES 42.2K F 1/16W 0402 | R2_SA;HF_SA;G_SA; | Released | TA-I ; RALEC ; CYNTEC ; YAGEO | RM04FTN4222 ; RTT024222FTH ; RR0510S-4222-FN ; RC0402FR-0742K2L | Multiple |  | Purchase | SMT | 1 | PCS | R9021 |
| 2 | 55.B0710.S11G | 64.44215.6DL | CHIP RES 4.42K F 1/16W 0402(RO | R2_SA;HF_SA;G_SA; | Released | CYNTEC;RALTEC;TAI;WALSIN;YAGEO | RR0510S-4421-FN;RTT024421FTH;RM04FTN4421;WR04X4421FTL;RC0402FR-074K42L | Multiple |  | Purchase | SMT | 1 | PCS | PR79 |
| 2 | 55.B0710.S11G | 64.44225.6DL | CHIP RES 44.2K F 1/16W 0402 | R2_SA;HF_SA;G_SA; | Released | TA-I;RALEC;CYNTEC;YAGEO;WALSIN | RTT024422FTH ; RR0510S-4422-FN ; RM04FTN4422 ; RC0402FR-0744K2L ; WR04X4422FTL | Multiple |  | Purchase | SMT | 1 | PCS | PR33 |
| 2 | 55.B0710.S11G | 64.47015.55L | CHIP RES 4.7K F 1/10W 0603 | R2_SA;HF_SA;G_SA; | Released | TA-I ; RALEC ; YAGEO | RM06FTN4701 ; RTT034701FTP ; RC0603FR-074K7L | Multiple |  | Purchase | SMT | 1 | PCS | R9025 |
| 2 | 55.B0710.S11G | 64.47015.6DL | CHIP RES 4.7K F 1/16W 0402 | R2_SA;HF_SA;G_SA; | Released | TA-I;RALEC;CYNTEC;YAGEO;WALSIN | RM04FTN4701;RTT024701FTH;RR0510S-472-FN;RC0402FR-074K7L;WR04X4701FTL | Multiple |  | Purchase | SMT | 146 | PCS | R160 R161 R163 R166 R167 R173 R174 R177 R178 R186 R195 R196 R2054 R2055 R216 R217 R222 R223 R227 R228 R248 R297 R314 R325 R326 R411 R436 R437 R477 R488 R489 R490 R493 R535 R550 R571 R578 R580 R581 R590 R592 R599 R602 R603 R606 R610 R611 R630 R633 R636 R637 R638 R639 R641 R642 R645 R647 R648 R649 R652 R655 R657 R7896 R7898 R799 R801 R802 R803 R804 SR1274 SR1278 SR1279 SR263 SR266 SR269 SR270 SR271 SR578 SR579 SR589 SR590 SR643 SR645 SR647 SR648 SR654 SR655 SR660 SR670 SR671 SR672 SR673 SR674 SR675 SR676 SR677 SR678 SR679 SR680 SR688 SR719 SR720 SR721 SR725 SR726 SR745 SR746 SR747 SR748 SR749 SR750 SR752 SR753 SR755 SR756 SR758 SR762 SR763 SR766 SR767 SR776 SR777 SR778 SR779 SR780 SR781 SR782 SR783 SR791 SR795 SR839 SR851 SR854 SR857 SR901 SR902 SR908 SR910 SR911 SR912 SR913 SR916 SR917 SR918 SR930 SR932 |
| 2 | 55.B0710.S11G | 64.47025.6DL | CHIP RES 47K F 1/16W 0402 | R2_SA;HF_SA;G_SA; | Released | TA-I;RALEC;CYNTEC;YAGEO;WALSIN | RM04FTN4702;RTT024702FTH;RR0510S-473-FN;RC0402FR-0747KL;WR04X4702FTL | Multiple |  | Purchase | SMT | 1 | PCS | R333 |
| 2 | 55.B0710.S11G | 64.47515.6DL | CHIP RES 4.75K F 1/16W 0402 | R2_SA;HF_SA;G_SA; | Released | TA-I;RALEC;CYNTEC;YAGEO | RM04FTN4751;RTT024751FTH;RR0510S-4751-FN;RC0402FR-074K75L | Multiple |  | Purchase | SMT | 44 | PCS | PR123 PR80 PR87 R383 R384 R390 R391 R392 R393 R394 R459 SR768 SR769 SR770 SR771 SR772 SR773 SR775 SR786 SR787 SR789 SR796 SR797 SR800 SR803 SR804 SR805 SR806 SR808 SR809 SR810 SR811 SR812 SR813 SR816 SR817 SR818 SR819 SR821 SR825 SR826 SR847 SR943 SR944 |
| 2 | 55.B0710.S11G | 64.47535.6DL | CHIP RES 475K F 1/16W 0402 | R2_SA;HF_SA;G_SA; | Released | TA-I;RALEC;CYNTEC;YAGEO | RM04FTN4753;RTT024753FTH;RR0510S-4753-FN;RC0402FR-07475KL | Multiple |  | Purchase | SMT | 3 | PCS | PR160 PR29 PR48 |
| 2 | 55.B0710.S11G | 64.48715.6DL | CHIP RES 4.87K F 1/16W 0402 | R2_SA;HF_SA;G_SA; | Released | TA-I;RALEC;CYNTEC;YAGEO | RM04FTN4871;RTT024871FTH;RR0510S-4871-FN;RC0402FR-074K87L | Multiple |  | Purchase | SMT | 1 | PCS | PR161 |
| 2 | 55.B0710.S11G | 64.49925.6DL | CHIP RES 49.9K F 1/16W 0402 | R2_SA;HF_SA;G_SA; | Released | TA-I ; RALEC ; CYNTEC ; YAGEO ; WALSIN | RM04FTN4992 ; RTT024992FTH ; RR0510S-4992-FN ; RC0402FR-0749K9L ; WR04X4992FTL | Multiple |  | Purchase | SMT | 3 | PCS | R2106 R2107 R337 |
| 2 | 55.B0710.S11G | 64.49R95.16L | CHIP RES 49.9 F 1/8W 0805 | R2_SA;HF_SA;G_SA; | Released | TAI;YAGEO;RALEC | RM10FTN49R9;RC0805FR-0749R9L;RTT0549R9FTP | Multiple |  | Purchase | SMT | 2 | PCS | R397 R398 |
| 2 | 55.B0710.S11G | 64.49R95.6DL | CHIP RES 49.9 F 1/16W 0402 | R2_SA;HF_SA;G_SA; | Released | TA-I;RALEC;CYNTEC;YAGEO;WALSIN | RM04FTN49R9;RTT0249R9FTH;RR0510S-49R9-FN;RC0402FR-0749R9L;WR04X49R9FTL | Multiple |  | Purchase | SMT | 3 | PCS | R401 R402 R7789 |
| 2 | 55.B0710.S11G | 64.49R96.6DL | CHIP RES 49.9 D 1/16W 0402 | R2_SA;HF_SA;G_SA; | Released | YAGEO;WALSIN;TA-I;CYNTEC;RALEC | RC0402DR-0749R9L;WF04H49R9DTL;RM04DTN49R9;RR0510R-49R9-DN;RTT0249R9DTH | Multiple |  | Purchase | SMT | 2 | PCS | R201 R202 |
| 2 | 55.B0710.S11G | 64.51R05.6DL | CHIP RES 51 F 1/16W 0402 | R2_SA;HF_SA;G_SA; | Released | TA-I;RALEC;CYNTEC;YAGEO;WALSIN | RM04FTN51R0;RTT0251R0FTH;RR0510S-510-FN;RC0402FR-0751RL;WR04X51R0FTL | Multiple |  | Purchase | SMT | 3 | PCS | SR582 SR585 SR586 |
| 2 | 55.B0710.S11G | 64.51R05.F9L | CHIP RES 51 F 3/4W 2010 | R2_SA;HF_SA;G_SA; | Released | TA-I ; RALEC ; YAGEO | RM20FEN51R0 ; RTT2051R0FTH ; RC2010FK-0751RL | Multiple |  | Purchase | SMT | 1 | PCS | R479 |
| 2 | 55.B0710.S11G | 64.53615.6DL | CHIP RES 5.36K F 1/16W 0402 | R2_SA;HF_SA;G_SA; | Released | TAI ; RALEC ;CYNTEC ;YAGEO | RM04FTN5361 ;RTT025361FTH ;RR0510S-5361-FN ;RC0402FR-075K36L | Multiple |  | Purchase | SMT | 1 | PCS | PR6888 |
| 2 | 55.B0710.S11G | 64.54925.6DL | CHIP RES 54.9K F 1/16W 0402 | R2_SA;HF_SA;G_SA; | Released | TA-I ; RALEC ; CYNTEC ; YAGEO | RM04FTN5492 ; RTT025492FTH ; RR0510S-5492-FN ; RC0402FR-0754K9L | Multiple |  | Purchase | SMT | 1 | PCS | PR10 |
| 2 | 55.B0710.S11G | 64.56015.6DL | CHIP RES 5.6K F 1/16W 0402(ROH | R2_SA;HF_SA;G_SA; | Released | TA-I;RALEC;CYNTEC;YAGEO;WALSIN | RM04FTN5601;RTT025601FTH;RR0510S-562-FN;RC0402FR-075K6L;WR04X5601FTL | Multiple |  | Purchase | SMT | 1 | PCS | R5764 |
| 2 | 55.B0710.S11G | 64.57625.6DL | CHIP RES 57.6K F 1/16W 0402 | R2_SA;HF_SA;G_SA; | Released | TAI;CYNTEC;YAGEO;RALEC | RM04FTN5762;RR0510S-5762-FN;RC0402FR-0757K6L;RTT025762FTH | Multiple |  | Purchase | SMT | 1 | PCS | R9023 |
| 2 | 55.B0710.S11G | 64.60415.6DL | CHIP RES 6.04K F 1/16W 0402 | R2_SA;HF_SA;G_SA; | Released | TA-I;RALEC;CYNTEC;YAGEO;WALSIN | RM04FTN6041;RTT026041FTH;RR0510S-6041-FN;RC0402FR-076K04L;WR04X6041FTL | Multiple |  | Purchase | SMT | 1 | PCS | R2109 |
| 2 | 55.B0710.S11G | 64.69825.6DL | CHIP RES 69.8K F 1/16W 0402 | R2_SA;HF_SA;G_SA; | Released | TA-I;RALEC;CYNTEC;YAGEO | RM04FTN6982;RTT026982FTH;RR0510S-6982-FN;RC0402FR-0769K8L | Multiple |  | Purchase | SMT | 1 | PCS | PR185 |
| 2 | 55.B0710.S11G | 64.73215.6DL | CHIP RES 7.32K F 1/16W 0402 | R2_SA;HF_SA;G_SA; | Released | TA-I;RALEC;CYNTEC;YAGEO;WALSIN | RM04FTN7321;RTT027321FTH;RR0510S-7321-FN;RC0402FR-077K32L;WR04X7321FTL | Multiple |  | Purchase | SMT | 1 | PCS | PR190 |
| 2 | 55.B0710.S11G | 64.73225.6DL | CHIP RES 73.2K F 1/16W 0402 | R2_SA;HF_SA;G_SA; | Released | TA-I;RALEC;CYNTEC;YAGEO;WALSIN | RM04FTN7322;RTT027322FTH;RR0510S-7322-FN;RC0402FR-0773K2L;WR04X7322FTL | Multiple |  | Purchase | SMT | 2 | PCS | PR31 PR51 |
| 2 | 55.B0710.S11G | 64.86625.6DL | CHIP RES 86.6K F 1/16W 0402 | R2_SA;HF_SA;G_SA; | Released | TA-I;RALEC;CYNTEC;YAGEO | RM04FTN8662;RTT028662FTH;RR0510S-8662-FN;RC0402FR-0786K6L | Multiple |  | Purchase | SMT | 1 | PCS | R9022 |
| 2 | 55.B0710.S11G | 64.95315.6DL | CHIP RES 9.53K F 1/16W 0402 | R2_SA;HF_SA;G_SA; | Released | TA-I;RALEC;CYNTEC;YAGEO | RM04FTN9531;RTT029531FTH;RR0510S-9531-FN;RC0402FR-079K53L | Multiple |  | Purchase | SMT | 1 | PCS | R9014 |
| 2 | 55.B0710.S11G | 64.R0025.L1L | CHIP RES 0.002 F 1W 0612 | R2_SA; | Released | CYNTEC | RL1632L4-R002-FN | Single |  | Purchase | SMT | 1 | PCS | R9020 |
| 2 | 55.B0710.S11G | 64.R0085.97L | CHIP RES 0.008 F 2W 2512 | R2_SA;HF_SA;G_SA; | Released | CYNTEC;TAI;YAGEO | RL-3264-9-R008-FN;RLM25FEER008;PF2512FKF7W0R008L | Multiple |  | Purchase | SMT | 1 | PCS | R520 |
| 2 | 55.B0710.S11G | 64.R5105.55L | CHIP RES 0.51 F 1/10W 0603 L/F | R2_SA;HF_SA;G_SA; | Released | RALEC ; TA-I ; YAGEO ; WALSIN | RTT03R510FTP ; RL06FTNR510 ; RL0603FR-070R51L ; WW06XR510FTL | Multiple |  | Purchase | SMT | 9 | PCS | SR715 SR716 SR827 SR831 SR832 SR833 SR834 SR835 SR836 |
| 2 | 55.B0710.S11G | 68.00084.771 | CHIP BEAD BLM41PG600SN1L MURAT | R2_SA; | Released | MURATA | BLM41PG600SN1L | Single |  | Purchase | SMT | 2 | PCS | PL10 PL8 |
| 2 | 55.B0710.S11G | 68.00084.831 | CHIP BEAD BLM21PG220SN1D (LF) | R2_SA;HF_SA; | Released | MURATA | BLM21PG220SN1D | Single |  | Purchase | SMT | 2 | PCS | PL2 PL4 |
| 2 | 55.B0710.S11G | 68.00084.A61 | CHIP BEAD BLM21PG300SN1D MURAT | R2_SA; | Released | MURATA | BLM21PG300SN1D | Single |  | Purchase | SMT | 1 | PCS | L7 |
| 2 | 55.B0710.S11G | 68.00109.171 | CHIP BEAD MMZ2012S601ATA1N TDK | R2_SA; | Released | TDK | MMZ2012S601ATA1N | Single |  | Purchase | SMT | 3 | PCS | L4 L5 L6 |
| 2 | 55.B0710.S11G | 68.00224.051 | CHIP BEAD MPZ2012S300AT TDK | R2_SA; | Released | TDK | MPZ2012S300AT | Single |  | Purchase | SMT | 8 | PCS | SL11 SL15 SL16 SL17 SL18 SL19 SL20 SL8 |
| 2 | 55.B0710.S11G | 68.00224.201 | CHIP BEAD MPZ2012S601AT TDK | R2_SA;HF_SA; | Released | TDK | MPZ2012S601AT | Single |  | Purchase | SMT | 11 | PCS | SL12 SL13 SL14 SL2 SL21 SL22 SL3 SL4 SL5 SL6 SL7 |
| 2 | 55.B0710.S11G | 68.00395.001 | CHIP BEAD 0181 28F0181-1SR-10 | R2_SA; | Released | LAIRD | 28F0181-1SR-10 | Single |  | Purchase | SMT | 1 | PCS | SL9 |
| 2 | 55.B0710.S11G | 68.2R21B.10J | CHIP IND 2.2UH MMD-06CZ-2R2M-V | R2_SA;HF_SA;G_SA; | Released | MAGLAYER | MMD-06CZ-2R2M-V1W | Single |  | Purchase | SMT | 1 | PCS | PL5 |
| 2 | 55.B0710.S11G | 68.3012N.10C | CHIP IND 300NH FP1007R3-R30-R | R2_SA; | Released | COOPER | FP1007R3-R30-R | Single |  | Purchase | SMT | 1 | PCS | PL9 |
| 2 | 55.B0710.S11G | 68.3R310.20V | CHIP CHOKE 3.3UH PCMB063T-3R3MS | R2_SA;HF_SA; | Released | CYNTEC | PCMB063T-3R3MS | Single |  | Purchase | SMT | 1 | PCS | PL12 |
| 2 | 55.B0710.S11G | 68.3R31A.20D | CHIP CHOKE 3.3UH M PCMB065T-3R3MS | R2_SA; | Released | CYNTEC | PCMB065T-3R3MS | Single |  | Purchase | SMT | 1 | PCS | PL3 |
| 2 | 55.B0710.S11G | 68.6R810.20P | CHIP CHOKE 6.8UH PCMB063T-6R8MS | R2_SA;HF_SA; | Released | CYNTEC | PCMB063T-6R8MS | Single |  | Purchase | SMT | 1 | PCS | PL1 |
| 2 | 55.B0710.S11G | 68.R4710.10M | CHIP CHOKE 0.47UH PCMC063T-R47 | R2_SA;HF_SA;G_SA; | Released | CYNTEC | PCMC063T-R47MN | Single |  | Purchase | SMT | 1 | PCS | PL11 |
| 2 | 55.B0710.S11G | 71.00551.00A | IC CLK BUF ICS551MLFT SOIC 8P | R2_SA; | Released | IDT | ICS551MLFT | Single |  | Purchase | SMT | 1 | PCS | U21 |
| 2 | 55.B0710.S11G | 71.01250.A0U | IC BMC AST1250A1-GP TFBGA 408P | R2_SA; | Released | ASPEED | AST1250A1-GP | Single |  | Purchase | SMT | 1 | PCS | U40 |
| 2 | 55.B0710.S11G | 71.02514.F03 | IC USB HUB USB2514B-AEZC-TR QFN 36P | R2_SA;HF_SA; | Released | SMSC | USB2514B-AEZC-TR | Single |  | Purchase | SMT | 1 | PCS | U183 |
| 2 | 55.B0710.S11G | 71.08563.A0A | IC RTC/CALENDAR PCF8563T SO8 | R2_SA;G_SA; | Released | NXP | PCF8563T/F4 | Single |  | Purchase | SMT | 1 | PCS | U43 |
| 2 | 55.B0710.S11G | 71.09306.00I | IC I2C BUS PCA9306DCTT SSOP 8P | R2_SA; | Released | TI | PCA9306DCTT | Multiple |  | Purchase | SMT | 7 | PCS | SU52 SU62 SU65 SU66 SU68 SU74 SU78 |
| 2 | 55.B0710.S11G | 71.09550.00W | IC LED DRV PCA9550DP TSSOP 8P | R2_SA; | Released | NXP | PCA9550DP | Single |  | Purchase | SMT | 1 | PCS | U12 |
| 2 | 55.B0710.S11G | 71.09552.00W | IC IC2 LED DRV PCA9552PW TSSOP | R_SA; | Released | NXP | PCA9552 | Single |  | Purchase | SMT | 1 | PCS | U188 |
| 2 | 55.B0710.S11G | 71.09575.00W | IC I2C BUS PCA9575PW2 TSSOP 28P | R2_SA; | Released | NXP | PCA9575PW2 | Single |  | Purchase | SMT | 1 | PCS | SU14 |
| 2 | 55.B0710.S11G | 71.P9511.00W | IC BUF PCA9511ADP-T TSSOP 8P | R2_SA; | Released | NXP | PCA9511ADP-T | Single |  | Purchase | SMT | 2 | PCS | U23 U24 |
| 2 | 55.B0710.S11G | 72.02464.A01 | IC EEPRM 24LC64-I/SN SO8 | R2_SA; | Released | MICROCHIP | 24LC64-I/SN | Single |  | Purchase | SMT | 1 | PCS | U16 |
| 2 | 55.B0710.S11G | 72.24C64.G01 | IC EEPROM AT24C64D-SSHM-T SOIC 8P | R2_SA;HF_SA; | Released | ATMEL | AT24C64D-SSHM-T | Single |  | Purchase | SMT | 2 | PCS | SU61 SU67 |
| 2 | 55.B0710.S11G | 72.29128.Z09 | IC FEROM S29GL128S10TFIV20 TSOP 56P | R2_SA; | Released | SPANSION | S29GL128S10TFIV20 | Single |  | Purchase | SMT | 2 | PCS | SU58 SU73 |
| 2 | 55.B0710.S11G | 72.56416.P0U | IC SDRAM NT5CB64M16FP-DH FBGA 96BALLS | R2_SA;HF_SA;G_SA; | Released | NANYA | NT5CB64M16FP-DH | Single |  | Purchase | SMT | 1 | PCS | U18 |
| 2 | 55.B0710.S11G | 73.00102.007 | IC TRANSLATOR TXS0102DCUR VSSOP 8P | R2_SA;HF_SA; | Released | TI | TXS0102DCUR | Single |  | Purchase | SMT | 3 | PCS | U184 U185 U186 |
| 2 | 55.B0710.S11G | 73.01G00.BHH | IC CMOS SN74LVC1G00DCKR DCK 5P | R2_SA;HF_SA;G_SA; | Released | TI | SN74LVC1G00DCKR | Single |  | Purchase | SMT | 1 | PCS | U44 |
| 2 | 55.B0710.S11G | 73.01G07.01H | IC BUF SN74LVC1G07DCKRG4 DCK5P | R2_SA; | Released | TI | SN74LVC1G07DCKRG4 | Single |  | Purchase | SMT | 1 | PCS | U32 |
| 2 | 55.B0710.S11G | 73.01G07.CHH | IC CMOS 74LVC1G07DCKR SC70-5 | R2_SA;HF_SA;G_SA; | Released | TI | SN74LVC1G07DCKR | Single |  | Purchase | SMT | 1 | PCS | U25 |
| 2 | 55.B0710.S11G | 73.01G08.L03 | IC CMOS SN74LVC1G08DCKR SC-70 | R2_SA;HF_SA;G_SA; | Released | TI | SN74LVC1G08DCKR | Single |  | Purchase | SMT | 9 | PCS | SU79 SU80 U172 U173 U177 U38 U39 U46 U50 |
| 2 | 55.B0710.S11G | 73.01G11.AHH | IC CMOS SN74LVC1G11DCKR DCK | R_SA;G_SA; | Released | TI | SN74LVC1G11DCKR | Single |  | Purchase | SMT | 1 | PCS | U45 |
| 2 | 55.B0710.S11G | 73.01G17.BHH | IC CMOS SN74LVC1G17DCKR DCK 5P | R2_SA;HF_SA; | Released | TI | SN74LVC1G17DCKR | Single |  | Purchase | SMT | 1 | PCS | PU99 |
| 2 | 55.B0710.S11G | 73.03861.G0C | IC BUS SW PI3C3861-AQE QSOP 24P | R2_SA; | Released | PERICOM | PI3C3861-AQE | Single |  | Purchase | SMT | 4 | PCS | SU13 SU15 SU16 SU18 |
| 2 | 55.B0710.S11G | 73.07414.FHB | IC CMOS 74LVC14APW TSSOP 14P | R2_SA; | Released | NXP | 74LVC14APW | Single |  | Purchase | SMT | 1 | PCS | U175 |
| 2 | 55.B0710.S11G | 73.1G126.DHG | IC CMOS SN74LVC1G126DCKR SC70 | R2_SA;HF_SA; | Released | TI | SN74LVC1G126DCKR | Single |  | Purchase | SMT | 4 | PCS | U171 U174 U178 U179 |
| 2 | 55.B0710.S11G | 73.2G07D.020 | IC BUF/DRV SN74LVC2G07DBVR SOT23-6 | R2_SA;HF_SA; | Released | TI | SN74LVC2G07DBVR | Single |  | Purchase | SMT | 1 | PCS | SU76 |
| 2 | 55.B0710.S11G | 73.2G125.0AB | IC DUAL-BUFFER/LIN 74HC2G125DP TSSOP8 | R2_SA; | Released | NXP | 74HC2G125DP | Single |  | Purchase | SMT | 2 | PCS | U192 U193 |
| 2 | 55.B0710.S11G | 73.74774.003 | IC BUS SN74AVC4T774RGYR QFN16P | R2_SA;HF_SA; | Released | TI | SN74AVC4T774RGYR | Single |  | Purchase | SMT | 1 | PCS | U181 |
| 2 | 55.B0710.S11G | 73.8T245.B29 | IC XCVR SN74LVC8T245DGVR TVSOP | R2_SA; | Released | TI | SN74LVC8T245DGVR | Single |  | Purchase | SMT | 4 | PCS | SU69 SU70 SU71 SU72 |
| 2 | 55.B0710.S11G | 74.00075.B79 | IC TEMP SENSOR TMP75AIDGKR MSOP 8P | R2_SA; | Released | TI | TMP75AIDGKR | Single |  | Purchase | SMT | 3 | PCS | U134 U135 U136 |
| 2 | 55.B0710.S11G | 74.00235.033 | IC S.R VT235WFQX-ADJ QFN 19P | R_C; | Released | VOLTERRA | VT235WFQX-ADJ | Single |  | Purchase | SMT | 1 | PCS | PU13 |
| 2 | 55.B0710.S11G | 74.00393.I21 | IC V.C LM393ADR SOIC 8P(ROHS) | R2_SA;HF_SA; | Released | TI | LM393ADR | Single |  | Purchase | SMT | 2 | PCS | U36 U41 |
| 2 | 55.B0710.S11G | 74.01178.079 | IC MONI ADM1178-2ARMZ-R7 MSOP | R2_SA; | Released | ADI | ADM1178-2ARMZ-R7 | Single |  | Purchase | SMT | 1 | PCS | U34 |
| 2 | 55.B0710.S11G | 74.02065.07F | IC PWR SW TPS2065DBVT SOT-23 5P | R2_SA;HF_SA; | Released | TI | TPS2065DBVT | Single |  | Purchase | SMT | 1 | PCS | U194 |
| 2 | 55.B0710.S11G | 74.03808.073 | IC RESET TPS3808G18DRVR QFN 6P | R2_SA; | Released | TI | TPS3808G18DRVR | Single |  | Purchase | SMT | 2 | PCS | SU57 SU75 |
| 2 | 55.B0710.S11G | 74.04214.079 | IC TEMP SEN TMP421AIDCNRG4 SOT23 8P | R2_SA; | Released | TI | TMP421AIDCNRG4 | Single |  | Purchase | SMT | 1 | PCS | U15 |
| 2 | 55.B0710.S11G | 74.23157.A99 | IC A.S TS5A23157DGSR DGS 10P | R2_SA;G_SA; | Released | TI | TS5A23157DGSR | Single |  | Purchase | SMT | 3 | PCS | U26 U27 U28 |
| 2 | 55.B0710.S11G | 74.53312.073 | IC PWM CTRL TPS53312RGTR QFN 16P | R2_SA; | Released | TI | TPS53312RGTR | Single |  | Purchase | SMT | 2 | PCS | PU1 PU100 |
| 2 | 55.B0710.S11G | 74.53318.073 | IC PWR CTRL TPS53318DQPR QFN 22P | R2_SA;HF_SA; | Released | TI | TPS53318DQPR | Single |  | Purchase | SMT | 2 | PCS | PU2 PU3 |
| 2 | 55.B0710.S11G | 74.53355.073 | IC PWM CTRL TPS53355DQPR QFN 22P | R2_SA; | Released | TI | TPS53355DQPR | Single |  | Purchase | SMT | 1 | PCS | PU12 |
| 2 | 55.B0710.S11G | 74.74801.A33 | IC LDO TPS74801RGW QFN 20P | R2_SA; | Released | TI | TPS74801RGW | Single |  | Purchase | SMT | 3 | PCS | PU10 PU5 PU6 |
| 2 | 55.B0710.S11G | 75.00054.E7D | IC DIODE S.B BAT54C-7-F SOT-23 3P | R2_SA;HF_SA;G_SA; | Released | DIODES | BAT54C-7-F | Single |  | Purchase | SMT | 1 | PCS | D13 |
| 2 | 55.B0710.S11G | 78.10134.1FL | CHIP CAP C 100P 50V J0402 NPO | R2_SA;HF_SA;G_SA; | Released | AVX;DARFON;MURATA;PHYCOMP;SAMSUNG;TAIYO;TDK;WALSIN;YAGEO | CM05CG101J50AH;C1005NP0101JGT;GRM1555C1H101JA01D;223886915101;CL05C101JB5NNNC;UMK105CH101JV-F;C1005C0G1H101JT;0402N101J500LT;CC0402JRNPO9BN101 | Multiple |  | Purchase | SMT | 3 | PCS | C193 C196 C203 |
| 2 | 55.B0710.S11G | 78.10224.2FL | CHIP CAP C 1000P 50V K0402 X7R | R2_SA;HF_SA;G_SA; | Released | AVX;DARFON;MURATA;PHYCOMP;SAMSUNG;TAIYO;TDK;MURATA;AVX;YAGEO | CM05X7R102K50AH;C1005X7R102KGT;GRM155R71H102KA01D;223858715623;CL05B102KB5NNNC;UMK105BJ102KV-F;C1005X7R1H102KT000F;WBM155R71H102KA01D;04025C102KAT2A;CC0402KRX7R9BB102 | Multiple |  | Purchase | SMT | 33 | PCS | C220 C221 C239 PC189 PC221 PC31 PC51 SC1009 SC1010 SC1011 SC1012 SC1013 SC1014 SC1015 SC1016 SC1029 SC1030 SC1031 SC1032 SC1033 SC1034 SC1035 SC1036 SC1211 SC1212 SC1213 SC1214 SC1215 SC1216 SC1217 SC1218 SC1219 SC1220 |
| 2 | 55.B0710.S11G | 78.10321.2FL | CHIP CAP C 0.01U 16V K0402 X7R | R2_SA;HF_SA;G_SA; | Released | AVX;DARFON;MURATA;PHYCOMP;SAMSUNG;TAIYO;TDK;WALSIN;MURATA;YAGEO | 0402YC103KAT2A;C1005X7R103KET;GRM155R71C103KA01D;223878715636;CL05B103KO5NNNC;EMK105BJ103KV-F;C1005X7R1C103KT000F;0402B103K160CT;WBM155R71C103KA01D;CC0402KRX7R7BB103 | Multiple |  | Purchase | SMT | 4 | PCS | C222 C224 C7273 SC877 |
| 2 | 55.B0710.S11G | 78.10322.2FL | CHIP CAP C 0.01U 25V K0402 X7R | R2_SA;HF_SA;G_SA; | Released | AVX;DARFON;MURATA;PHYCOMP;SAMSUNG;TAIYO;TDK;MURATA;YAGEO | 04023C103KAT2A;C1005X7R103KFT;GRM155R71E103KA01D;223891715636;CL05B103KA5NNNC;TMK105BJ103KV-F;C1005X7R1E103KT000F;WBM155R71E103KA01D;CC0402KRX7R8BB103 | Multiple |  | Purchase | SMT | 2 | PCS | C177 C179 |
| 2 | 55.B0710.S11G | 78.10323.20L | CHIP CAP C 0.01U 10V K0201 X7R | R2_SA;HF_SA;G_SA; | Released | MURATA;PHYCOMP;YAGEO;DARFON | GRM033R71A103KA01D;223824815636;CC0201KRX7R6BB103;C0603X7R103KDT | Multiple |  | Purchase | SMT | 64 | PCS | SC1067 SC1068 SC1069 SC1070 SC1071 SC1072 SC1073 SC1074 SC1075 SC1076 SC1077 SC1078 SC1079 SC1080 SC1081 SC1082 SC1083 SC1084 SC1085 SC1086 SC1087 SC1088 SC1089 SC1090 SC1091 SC1092 SC1093 SC1094 SC1095 SC1096 SC1097 SC1102 SC1103 SC1104 SC1105 SC1261 SC1262 SC1263 SC1264 SC1265 SC1266 SC1267 SC1268 SC1269 SC1270 SC1271 SC1272 SC1273 SC878 SC879 SC880 SC881 SC882 SC883 SC884 SC885 SC890 SC891 SC892 SC893 SC894 SC895 SC901 SC902 |
| 2 | 55.B0710.S11G | 78.10324.2BL | CHIP CAP C 0.01U 50V K0603 X7R | R2_SA;HF_SA;G_SA; | Released | AVX;KEMET;MURATA;PHYCOMP;SAMSUNG;TDK;DARFON;PANASONIC;WALSIN | 06035C103KAT2A;C0603C103K5RAC;GRM188R71H103KA01D;223858615636;CL10B103KB8NNNC;C1608X7R1H103KT;C1608X7R103KGT;ECJ1VB1H103K;0603B103K500CT | Multiple |  | Purchase | SMT | 3 | PCS | PC210 PC211 PC218 |
| 2 | 55.B0710.S11G | 78.10324.2FL | CHIP CAP C 0.01U 50V K0402 X7R | R2_SA;HF_SA;G_SA; | Released | MURATA;PHYCOMP;DARFON;TDK;SAMSUNG;WALSIN;MURATA | GRM155R71H103KA88D;223858715636;C1005X7R103KGT;C1005X7R1H103KT;CL05B103KB5NNNC;0402B103K500CT;WBM155R71H103KA01D | Multiple |  | Purchase | SMT | 21 | PCS | C129 C130 C131 C132 C133 C134 C135 C136 C143 C242 C244 SC1065 SC1109 SC1274 SC1275 SC1276 SC1277 SC1278 SC1279 SC1280 SC1281 |
| 2 | 55.B0710.S11G | 78.10420.50L | CHIP CAP C 0.1U 6.3V K0201 X5R | R2_SA;HF_SA;G_SA; | Released | MURATA;AVX;DARFON;WALSIN;MATSUKI;TAIYO ;SAMSUNG | GRM033R60J104KE19D;02016D104KAT2A;C0603X5R104KCT;0201X104K6R3CT;MAG01X5R0J104K;RMJMK063BJ104KP-F;CL03A104KQ3NNNC | Multiple |  | Purchase | SMT | 99 | PCS | SC1134 SC1135 SC1136 SC1137 SC1138 SC1139 SC1140 SC1141 SC1142 SC1143 SC1144 SC1145 SC1149 SC1153 SC1157 SC1161 SC1162 SC1163 SC1167 SC1168 SC1169 SC1179 SC1180 SC1181 SC1185 SC1186 SC1187 SC1191 SC1192 SC1193 SC1197 SC1201 SC1221 SC1222 SC1223 SC1224 SC1225 SC1226 SC1227 SC1228 SC1229 SC1230 SC1231 SC1232 SC1233 SC1234 SC1235 SC1236 SC1237 SC1238 SC1239 SC1240 SC1241 SC1242 SC1243 SC1244 SC1245 SC1246 SC1247 SC1248 SC1249 SC1250 SC1251 SC1252 SC1253 SC1254 SC1255 SC1256 SC1257 SC1258 SC1259 SC1260 SC918 SC922 SC926 SC930 SC934 SC938 SC939 SC940 SC942 SC943 SC944 SC948 SC949 SC950 SC951 SC952 SC953 SC954 SC955 SC959 SC960 SC961 SC962 SC963 SC964 SC965 SC966 |
| 2 | 55.B0710.S11G | 78.10421.2BL | CHIP CAP C 0.1U 16V K0603 X7R | R2_SA;HF_SA;G_SA; | Released | AVX;DARFON;MURATA;PHYCOMP;SAMSUNG;TAIYO;TDK;WALSIN | 0603YC104KAT2A;C1608X7R104KET;GRM188R71C104KA01D;223878615649;CL10B104KO8NNNC;EMK107BJ104KA-T;C1608X7R1C104KT;0603B104K160CT | Multiple |  | Purchase | SMT | 2 | PCS | PC35 PC55 |
| 2 | 55.B0710.S11G | 78.10421.2FL | CHIP CAP C 0.1U 16V K0402 X7R | R2_SA;HF_SA;G_SA; | Released | DARFON;MURATA;PHYCOMP;SAMSUNG;TAIYO;TDK;WALSIN;YAGEO | C1005X7R104KET;GRM155R71C104KA88D;223878715649;CL05B104KO5NNNC;EMK105BJ104KV-FR ;C1005X7R1C104KT000F;0402B104K160CT;CC0402KRX7R7BB104 | Multiple |  | Purchase | SMT | 196 | PCS | C142 C146 C151 C171 C172 C173 C174 C175 C176 C178 C181 C182 C183 C184 C185 C186 C187 C195 C202 C223 C225 C228 C229 C230 C231 C236 C241 C243 C249 C263 C264 C269 C272 C3 C319 C322 C323 C324 C325 C326 C327 C328 C333 C4 C41 C42 C43 C5 C7272 C7788 C81 C82 C83 C84 C85 C86 C87 C88 C89 C90 PC102 PC138 PC148 PC186 PC225 PC234 PC78 PC88 PC90 SC1000 SC1001 SC1002 SC1003 SC1004 SC1005 SC1006 SC1007 SC1008 SC1037 SC1038 SC1039 SC1040 SC1041 SC1042 SC1043 SC1044 SC1045 SC1046 SC1047 SC1048 SC1049 SC1050 SC1051 SC1052 SC1053 SC1054 SC1055 SC1056 SC1057 SC1058 SC1059 SC1060 SC1061 SC1062 SC1063 SC1064 SC1066 SC1098 SC1099 SC1100 SC1101 SC1106 SC1107 SC1108 SC1110 SC1111 SC1112 SC1113 SC1114 SC1115 SC1116 SC1117 SC1118 SC1119 SC1120 SC1121 SC1122 SC1123 SC1173 SC1174 SC1175 SC1282 SC1283 SC1284 SC1285 SC1286 SC1287 SC1290 SC1291 SC1292 SC1293 SC1294 SC1295 SC1297 SC1298 SC1299 SC1300 SC1301 SC1303 SC1306 SC1307 SC1311 SC307 SC308 SC427 SC428 SC429 SC431 SC433 SC435 SC436 SC545 SC546 SC547 SC564 SC634 SC860 SC867 SC914 SC973 SC974 SC975 SC976 SC977 SC978 SC979 SC980 SC981 SC982 SC983 SC984 SC985 SC986 SC987 SC988 SC989 SC990 SC991 SC992 SC993 SC994 SC995 SC996 SC997 SC998 SC999 |
| 2 | 55.B0710.S11G | 78.10422.2BL | CHIP CAP C 0.1U 25V K0603 X7R | R2_SA;HF_SA;G_SA; | Released | AVX;DARFON;MURATA;PHYCOMP;SAMSUNG;TAIYO;TDK;WALSIN;YAGEO | 06033C104KAT2A;C1608X7R104KFT;GRM188R71E104KA01D;223891615649;CL10B104KA8NNNC;TMK107BJ104KA-T;C1608X7R1E104KT;0603B104K250CT;CC0603KRX7R8BB104 | Multiple |  | Purchase | SMT | 7 | PCS | C267 C274 C312 C7274 PC25 PC45 PC6 |
| 2 | 55.B0710.S11G | 78.10422.2FL | CHIP CAP C 0.1U 25V K0402 X7R | R2_SA;HF_SA;G_SA; | Released | YAGEO;WALSIN;MURATA;TDK | CC0402KRX7R8BB104;0402B104K250CT;GRM155R71E104KE14D;C1005X7R1E104KT | Multiple |  | Purchase | SMT | 41 | PCS | C256 C259 C261 C262 C271 C275 C277 C279 C280 C282 C283 C285 C286 C288 C289 C290 C291 C292 C293 C294 C295 C297 C298 C301 C303 C309 C310 C329 C330 C331 C340 C8081 C8083 C8084 C8085 C8086 C8087 C8088 C8089 PC30 PC50 |
| 2 | 55.B0710.S11G | 78.10423.2FL | CHIP CAP C 0.1U 10V K0402 X7R | R2_SA;HF_SA;G_SA; | Released | MURATA;PHYCOMP;SAMSUNG;TAIYO;TDK;DARFON;WALSIN;MURATA;YAGEO | GRM155R71A104KA01D;223824715649;CL05B104KP5NNNC;RMLMK105BJ104KV-F;C1005X7R1A104KT000F;C1005X7R104KDT;0402B104K100CT;WBM155R71A104KA01D;CC0402KRX7R6BB104 | Multiple |  | Purchase | SMT | 3 | PCS | PC146 PC86 PC99 |
| 2 | 55.B0710.S11G | 78.10424.2BL | CHIP CAP C 0.1U 50V K0603 X7R | R2_SA;HF_SA;G_SA; | Released | MURATA;TDK;AVX;PHYCOMP;SAMSUNG;DARFON;MATSUKI;WALSIN | GRM188R71H104KA93D;C1608X7R1H104KT000N;06035C104KAT2A;223858615649;CL10B104KB8NNNC;C1608X7R104KGT;MAG03X7R1H104K;0603B104K500CT | Multiple |  | Purchase | SMT | 9 | PCS | PC10 PC172 PC185 PC195 PC219 PC223 PC229 PC27 PC47 |
| 2 | 55.B0710.S11G | 78.10431.2FL | CHIP CAP 0.1UF J 16V 0402 X7R | R2_SA;HF_SA;G_SA; | Released | KEMET;TDK;MURATA;PHYCOMP;DARFON;SAMSUNG;WALSIN | C0402C104J4RAC;C1005X7R1C104JT;GRM155R71C104JA88D;223878715549;C1005X7R104JET;CL05B104JO5NNNC;0402B104J160CT | Multiple |  | Purchase | SMT | 4 | PCS | C152 C238 C240 C332 |
| 2 | 55.B0710.S11G | 78.10432.2BL | CHIP CAP C 0.1U 25V J0603 X7R | R2_SA;HF_SA;G_SA; | Released | PHYCOMP;WALSIN;DARFON | 223891615549;0603B104J250CT;C1608X7R104JFT | Multiple |  | Purchase | SMT | 3 | PCS | C7278 C7316 C7317 |
| 2 | 55.B0710.S11G | 78.10510.5SL | CHIP CAP C 1U 6.3V M0201 X5R | R2_SA;HF_SA;G_SA; | Released | MURATA;DARFON;TAIYO;SAMSUNG;AVX | GRM033R60J105MEA2D;C0603X5R105MCT;JDK063BJ105MP-FD;CL03A105MQ3CSNH;CV03X5R105M06AH | Multiple |  | Purchase | SMT | 20 | PCS | SC1133 SC1148 SC1152 SC1156 SC1160 SC1166 SC1178 SC1184 SC1190 SC1196 SC1200 SC917 SC921 SC925 SC929 SC933 SC937 SC941 SC947 SC958 |
| 2 | 55.B0710.S11G | 78.10520.2BL | CHIP CAP C 1U 6.3V K0603 X7R | R2_SA;HF_SA;G_SA; | Released | MURATA;TAIYO;DARFON;WALSIN;PHYCOMP;SAMSUNG | GRM188R70J105K;JMK107B7105KA-T;C1608X7R105KCT;0603B105K6R3CT;225520615663;CL10B105KQ8NNNC | Multiple |  | Purchase | SMT | 10 | PCS | C192 C194 C201 C210 C232 C233 C255 C317 C370 C371 |
| 2 | 55.B0710.S11G | 78.10521.2BL | CHIP CAP C 1U 16V K0603 X7R | R2_SA;HF_SA;G_SA; | Released | KEMET;MURATA;TAIYO;TDK;PHYCOMP;WALSIN;SAMSUNG;DARFON | C0603C105K4RAC;GRM188R71C105KA12D;EMK107B7105KA-T;C1608X7R1C105KT;223878615663;0603B105K160CT;CL10B105KO8NNNC;C1608X7R105KET | Multiple |  | Purchase | SMT | 8 | PCS | C180 C316 C7275 C7276 C7277 PC13 PC224 PC232 |
| 2 | 55.B0710.S11G | 78.10521.5BL | CHIP CAP C 1U 16V K0603 X5R | R2_SA;HF_SA;G_SA; | Released | AVX;DARFON;MURATA;PHYCOMP;SAMSUNG;TAIYO;TDK;WALSIN;YAGEO | CM105X5R105K16AT;C1608X5R105KET;GRM188R61C105KA93D;223878613663;CL10A105KO8NNNC;EMK107BJ105KA-T;C1608X5R1C105KT;0603X105K160CT;CC0603KRX5R7BB105 | Multiple |  | Purchase | SMT | 1 | PCS | PC190 |
| 2 | 55.B0710.S11G | 78.10522.2BL | CHIP CAP C 1U 25V K0603 X7R | R2_SA;HF_SA;G_SA; | Released | MURATA;TAIYO;TDK;WALSIN;SAMSUNG;DARFON | GRM188R71E105KA12D;TMK107BJ105KA-T;C1608X7R1E105KT;CL10B105KA8NNNC;C1608X7R105KFT | Multiple |  | Purchase | SMT | 16 | PCS | C253 C258 C278 C281 C284 C287 C299 C302 C311 PC207 PC208 PC209 PC212 PC213 PC215 PC5 |
| 2 | 55.B0710.S11G | 78.10522.5BL | CHIP CAP C 1U 25V K0603 X5R | R2_SA;HF_SA;G_SA; | Released | MURATA;TDK;PHYCOMP;TAIYO;MATSUKI;DARFON;TDK;WALSIN;SAMSUNG;YAGEO | GRM188R61E105KA12D;C1608X5R1E105KT000N;223891613663;TMK107BJ105KA-T;MAG03X5R1E105K;C1608X5R105KFT;C1608X5R1E105KT000N;0603X105K250CT;CL10A105KA8NNNC;CC0603KRX5R8BB105 | Multiple |  | Purchase | SMT | 1 | PCS | PC1083 |
| 2 | 55.B0710.S11G | 78.10523.2BL | CHIP CAP C 1U 10V K0603 X7R | R2_SA;HF_SA;G_SA; | Released | MURATA;TAIYO;TDK;WALSIN;SAMSUNG;DARFON | GRM188R71A105KA61D;LMK107B7105KA;C1608X7R1A105KT;0603B105K100CT;CL10B105KP8NNNC;C1608X7R105KDT | Multiple |  | Purchase | SMT | 20 | PCS | C197 C198 C199 C200 C204 C207 C219 C304 C305 C334 C335 C336 C337 C338 PC29 PC49 SC426 SC430 SC432 SC434 |
| 2 | 55.B0710.S11G | 78.10523.5FL | CHIP CAP C 1U 10V K0402 X5R | R2_SA;HF_SA;G_SA; | Released | MURATA;TDK;DARFON;MATSUKI;PHYCOMP;TAIYO;SAMSUNG;WALSIN | GRM155R61A105KE15D;C1005X5R1A105KT;C1005X5R105KDT;MAG02X5R1A105K;223824713663;LMK105BJ105KVF;CL05A105KP5NNNC;0402X105K100CT | Multiple |  | Purchase | SMT | 11 | PCS | C205 C206 C208 C212 C213 C214 C215 C216 C217 C218 PC20 |
| 2 | 55.B0710.S11G | 78.10523.8FL | CHIP CAP C 1U 10V K 0402 X6S | R2_SA;HF_SA; | Released | TAIYO;MURATA;TDK;SAMSUNG | LMK105C6105KV-F;GRM155C81A105KA12D;C1005X6S1A105KT;CL05X105KP5NNNC | Multiple |  | Purchase | SMT | 24 | PCS | C145 C155 C158 C159 C162 C163 C166 C167 C254 C320 SC1023 SC1024 SC1025 SC1026 SC1027 SC1028 SC1172 SC1289 SC967 SC968 SC969 SC970 SC971 SC972 |
| 2 | 55.B0710.S11G | 78.10524.5BL | CHIP CAP C 1U 50V K0603 X5R | R2_SA;HF_SA;G_SA; | Released | MURATA;TAIYO;DARFON;SAMSUNG;PHYCOMP;TDK | GRM188R61H105KAALD;UMK316BJ105KL-T;C1608X5R105KGT;CL10A105KB8NNNC;223858613663;CC0603KRX5R9BB105;C1608X5R1H105KT | Multiple |  | Purchase | SMT | 1 | PCS | PC193 |
| 2 | 55.B0710.S11G | 78.10620.21L | CHIP CAP C 10U 6.3V K0805 X7R | R2_SA;HF_SA;G_SA; | Released | MURATA;TAIYO;DARFON;AVX KYOCERA | GRM21BR70J106K;JMK212B7106KG-T;C2012X7R106KC; CM21X7R106K06AT | Multiple |  | Purchase | SMT | 28 | PCS | C170 SC1017 SC1018 SC1019 SC1020 SC1021 SC1022 SC1147 SC1151 SC1155 SC1195 SC1199 SC1202 SC1203 SC1204 SC1205 SC1206 SC1207 SC1208 SC1209 SC1210 SC1288 SC916 SC920 SC924 SC928 SC932 SC936 |
| 2 | 55.B0710.S11G | 78.10620.51L | CHIP CAP C 10UF 6.3V K0805 X5R | R2_SA;HF_SA;G_SA; | Released | MURATA;AVX;TDK;TAIOY;PHYCOMP;DARFON;SAMSUNG;MATSUK | GRM21BR60J106KE19L ; CM21X5R106K06AT ; C2012X5R0J106KT000N; JMK212BJ106KG-T ; 225020013676 ; C2012X5R106KCT ; CL21A106KQFNNNE ;MAG05X5R0J106K | Multiple |  | Purchase | SMT | 19 | PCS | C227 PC139 PC140 PC142 PC143 PC144 PC145 PC79 PC80 PC82 PC83 PC84 PC85 PC91 PC92 PC94 PC95 PC96 PC97 |
| 2 | 55.B0710.S11G | 78.10622.52L | CHIP CAP C 10U 25V K1206 X5R | R2_SA;HF_SA;G_SA; | Released | TAIYO;MURATA;AVX;TDK;KEMET;MATSUKI;PHYCOMP;DARFON;SAMSUNG | TMK316BJ106KL-T;GRM31CR61E106KA12L;12063D106KAT2A;C3216X5R1E106KT;C1206C106K3PAC;MAG06X5R1E106K;222291113676;C3216X5R106KFP;CL31A106KAHNNNE | Multiple |  | Purchase | SMT | 3 | PCS | PC204 PC205 PC206 |
| 2 | 55.B0710.S11G | 78.10710.52L | CHIP CAP C 100U 6.3V M1206 X5R | R2_SA;HF_SA;G_SA; | Released | MURATA;TAIYO | GRM31CR60J107ME39L;JMK316BJ107ML | Multiple |  | Purchase | SMT | 7 | PCS | PC37 PC38 PC39 PC40 PC57 PC58 PC59 |
| 2 | 55.B0710.S11G | 78.10710.53L | CHIP CAP C 100U 6.3V M1210 X5R | R2_SA;HF_SA;G_SA; | Released | MURATA;TAIYO;TDK;KEMET;TAIYO;SAMSUNG | GRM32ER60J107ME20L;JMK325BJ107MM-T;C3225X5R0J107MT000N;C1210C107M9PAC;JMK325ABJ107MM-P;CL32A107MQVNNNE | Multiple |  | Purchase | SMT | 11 | PCS | SC1131 SC1132 SC1158 SC1164 SC1170 SC1176 SC1182 SC1188 SC945 SC956 SC957 |
| 2 | 55.B0710.S11G | 78.12034.1FL | CHIP CAP C 12P 50V J0402 NPO | R2_SA;HF_SA;G_SA; | Released | AVX;MURATA;PHYCOM;TAIYO;TDK;DARFON;MURATA;WALSIN | 04025A120JAT2A;GRM1555C1H120JZ01D;223886915129;UMK105CH120JW-F;C1005C0G1H120J;C1005NP0120JGT;GRM1555C1H120JA01D;0402N120J500 | Multiple |  | Purchase | SMT | 4 | PCS | SC1124 SC1125 SC886 SC887 |
| 2 | 55.B0710.S11G | 78.15322.2FL | CHIP CAP C 0.015U 25V K0402 X7R | R2_SA;HF_SA;G_SA; | Released | MURATA;TDK;WALSIN;DARFON;PHYCOMP | GRM155R71E153KA61D;C1005X7R1E153KT000F;0402B153K250CT;C1005X7R153KFT;223891715638 | Multiple |  | Purchase | SMT | 1 | PCS | C372 |
| 2 | 55.B0710.S11G | 78.18034.1BL | CHIP CAP 18P50V J0603 NPO(ROHS | R2_SA;HF_SA;G_SA; | Released | MURATA;PHYCOMP;TDK;TAIYO;SAMSUNG;DARFON;AVX;WALSIN | GRM1885C1H180JA01D;223886715189;C1608C0G1H180JT;UMK107CG180JZ-T;CL10C180JB8NNNC;C1608NPO180JGT;06035A180JAT2A;0603N180J500LT | Multiple |  | Purchase | SMT | 2 | PCS | C8090 C8091 |
| 2 | 55.B0710.S11G | 78.22124.2FL | CHIP CAP C 220P 50V K0402 X7R | R2_SA;HF_SA;G_SA; | Released | MURATA;AVX;TAIYO;PHYCOMN;DARFON | GRM155R71H221KA01D;04025C221KAT2A;UMK105BJ221KV-F;223858715614;C1005X7R221KGT | Multiple |  | Purchase | SMT | 3 | PCS | C209 C211 PC217 |
| 2 | 55.B0710.S11G | 78.22224.2FL | CHIP CAP C 2200P 50V K0402 X7R | R2_SA;HF_SA;G_SA; | Released | MURATA;AVX;TDK;TAIYO;PHYCOMN;DARFON;SAMSUNG;WALSIN;YAGEO | GRM155R71H222KA01D;04025C222KAT2A;C1005X7R1H222KT000F;UMK105BJ222KV-F;223858715627;C1005X7R222KGT;CL05B222KB5NNNC;0402B222K500CT;CC0402KRX7R9BB222 | Multiple |  | Purchase | SMT | 1 | PCS | C266 |
| 2 | 55.B0710.S11G | 78.22410.5SL | CHIP CAP C 0.22U 6.3V M0201 X5R | R2_SA;HF_SA;G_SA; | Released | MURATA ; DARFON ; SAMSUNG ; TAIYO ; MURATA | GRM033R60J224ME15D ; C0603X5R224MCT ; CL03A224MQ3NNNH ;JMK063BJ224MP-F ; GRM033R60J223KE | Multiple |  | Purchase | SMT | 16 | PCS | SC1296 SC861 SC862 SC863 SC864 SC865 SC866 SC868 SC869 SC870 SC871 SC872 SC873 SC874 SC875 SC876 |
| 2 | 55.B0710.S11G | 78.22523.5BL | CHIP CAP C 2.2U 10V K 0603 X5R | R2_SA;HF_SA;G_SA; | Released | MURATA;TAIYO;SAMSUNG;TDK;PHYCOMP;PANASONIC;DARFON;WALSIN | GRM188R61A225KD;LMK107BJ225KA-T;CL10A225KP8NNNC;C1608X5R1A225KT000N;223824613667;ECJ1VB1A225K;C1608X5R225KDT;0603X225K100CT | Multiple |  | Purchase | SMT | 2 | PCS | BC1 BC2 |
| 2 | 55.B0710.S11G | 78.22610.51L | CHIP CAP C 22U 6.3V M0805 X5R | R2_SA;HF_SA;G_SA; | Released | MURATA;TAIYO;TDK;KEMET;PANASONIC;MATSUKI;SAMSUNG;DARFON;WALSIN;YAGEO;AVX | GRM21BR60J226ME39L;JMK212BJ226MG-T;C2012X5R0J226MT;C0805C226M9PAC;ECJ2FB0J226M;MAG05X5R0J226M;CL21A226MQQNNNE;C2012X5R226MCP;0805X226M6R3CT;CC0805MKX5R5BB226;CV21X5R226M06AT | Multiple |  | Purchase | SMT | 22 | PCS | C1698 C339 PC235 PC236 SC1146 SC1150 SC1154 SC1159 SC1165 SC1171 SC1177 SC1183 SC1189 SC1194 SC1198 SC915 SC919 SC923 SC927 SC931 SC935 SC946 |
| 2 | 55.B0710.S11G | 78.22610.5BL | CHIP CAP C 22U 6.3V M0603 X5R | R2_SA;HF_SA;G_SA; | Released | MURATA;TDK;SAMSUNG;TAIYO;DARFON | GRM188R60J226MEA0D;C1608X5R0J226MT;CL10A226MQ8NRNC;JDK107BBJ226MA-T;C1608X5R226MCT | Multiple |  | Purchase | SMT | 6 | PCS | PC176 PC177 PC178 PC179 PC36 PC56 |
| 2 | 55.B0710.S11G | 78.22612.51L | CHIP CAP C 22U 25V M0805 X5R | R2_SA;HF_SA;G_SA; | Released | MURATA;SANSUNG;DARFON;TDK | GRM21BR61E226ME44L;CL21A226MAQNNNE;C2012X5R226MFP;C2012X5R1E226MT | Multiple |  | Purchase | SMT | 25 | PCS | C257 C270 C276 C296 C300 C308 PC169 PC170 PC171 PC173 PC174 PC175 PC21 PC216 PC22 PC226 PC227 PC23 PC24 PC41 PC42 PC43 PC44 PC7 PC8 |
| 2 | 55.B0710.S11G | 78.22613.51L | CHIP CAP C 22U 10V M0805 X5R | R2_SA;HF_SA;G_SA; | Released | SAMSUNG;PHYCOMP;MURATA;TAIYO;TDK;SAMSUNG;DARFON | CL21A226MPQNNNG;222224013781;GRM21BR61A226ME51L;LMK212BJ226MG-T;C2012X5R1A226MT;CL21A226MPCLRNC;C2012X5R226MDP | Multiple |  | Purchase | SMT | 2 | PCS | PC15 PC16 |
| 2 | 55.B0710.S11G | 78.22620.22L | CHIP CAP C 22U 6.3V K 1206 X7R | R2_SA;HF_SA;G_SA; | Released | YAGEO;MURATA;KYOCERA;SAMSUNG | CC1206KKX7R5BB226;GRM31CR70J226KE19L;CM316X7R226K06AT;CL31B226KQHNNNE | Multiple |  | Purchase | SMT | 8 | PCS | PC196 PC197 PC198 PC199 PC200 PC201 PC202 PC203 |
| 2 | 55.B0710.S11G | 78.33224.2FL | CHIP CAP C 3300P 50V K0402 X7R | R2_SA;HF_SA;G_SA; | Released | MURATA;AVX;TDK;TAIYO;PHYCOMN;DARFON | GRM155R71H332KA01D;04025C332KAT2A;C1005X7R1H332KT000F;UMK105BJ332KV-F;223858715629;C1005X7R332KGT | Multiple |  | Purchase | SMT | 2 | PCS | PC11 PC230 |
| 2 | 55.B0710.S11G | 78.33324.2BL | CHIP CAP 0.033U 50V K0603 X7R | R2_SA;HF_SA;G_SA; | Released | MURATA;AVX;PHYCOMP;DARFON | GRM188R71H333KA61D;06035C333KAT2A;223858615643;C1608X7R333KGT | Multiple |  | Purchase | SMT | 1 | PCS | C7279 |
| 2 | 55.B0710.S11G | 78.33420.5FL | CHIP CAP C 0.33U 6.3V K0402 X5 | R2_SA;HF_SA;G_SA; | Released | MURATA;TDK | GRM155R60J334KE01D;C1005X5R0J334KT000F | Multiple |  | Purchase | SMT | 1 | PCS | PC222 |
| 2 | 55.B0710.S11G | 78.47124.2FL | CHIP CAP C 470P50V K0402 X7R | R2_SA;HF_SA;G_SA; | Released | AVX;DARFON;MURATA;PHYCOMP;TAIYO;TDK;SAMSUNG;WALSIN;YAGEO | 04025C471KAT2A;C1005X7R471KGT;GRM155R71H471KA01D;223858715618;UMK105BJ471KV-F;C1005X7R1H471KT000F;CL05B471KB5NNNC;0402B471K500CT;CC0402KRX7R9BB471 | Multiple |  | Purchase | SMT | 3 | PCS | PC100 PC147 PC87 |
| 2 | 55.B0710.S11G | 78.47321.2FL | CHIP CAP C 0.047U 16V K0402 X7 | R2_SA;HF_SA;G_SA; | Released | MURATA;PHYCOMP;TAIYO;TDK;WALSIN;DARFON;SAMSUNG;YAGEO | GRM155R71C473KA01D;223878715645;EMK105BJ473KV-F;C1005X7R1C473KT000F;0402B473K160CT;C1005X7R473KET;CL05B473KO5NNNC;CC0402KRX7R7BB473 | Multiple |  | Purchase | SMT | 1 | PCS | C265 |
| 2 | 55.B0710.S11G | 78.47422.2BL | CHIP CAP C 0.47U 25V K0603 X7R | R2_SA;HF_SA;G_SA; | Released | MURATA;SAMSUNG;DARFON | GRM188R71E474KA12D;CL10B474KA8NNNC;C1608X7R474KFT | Multiple |  | Purchase | SMT | 3 | PCS | PC137 PC191 PC192 |
| 2 | 55.B0710.S11G | 78.47610.51L | CHIP CAP C 47U 6.3V M0805 X5R | R2_SA;HF_SA;G_SA; | Released | TAIYO;SAMSUNG;MURATA;TDK | JMK212BJ476MG-T;CL21A476MQYNNNE;GRM21BR60J476ME15;C2012X5R0J476MT00HE | Multiple |  | Purchase | SMT | 6 | PCS | PC180 PC181 PC182 PC183 PC237 PC238 |
| 2 | 55.B0710.S11G | 78.47611.53L | CHIP CAP C 47U 16V M1210 X5R | R2_SA;HF_SA;G_SA; | Released | MURATA;TAIYO;TAIYO | GRM32ER61C476ME15L;EMK325BJ476MM-T;EMK325BJ476MM-P | Multiple |  | Purchase | SMT | 5 | PCS | TC10 TC11 TC12 TC13 TC14 |
| 2 | 55.B0710.S11G | 78.47613.52L | CHIP CAP C 47U 10V M1206 X5R | R2_SA;HF_SA;G_SA; | Released | MURATA;TAIYO;WALSIN;SAMSUNG;PHYCOMP | GRM31CR61A476ME15L ; LMK316BJ476ML-T ; 1206X476M100CT;CL31A476MPHNNNE;225024113785 | Multiple |  | Purchase | SMT | 2 | PCS | PC17 PC18 |
| 2 | 55.B0710.S11G | 78.68224.2BL | CHIP CAP 6800P 50V K0603 X7R | R2_SA;HF_SA;G_SA; | Released | WALSIN;AVX;DARFON;MURATA;PHYCOMP;TDK | 0603B682K500CT;06035C682KAT2A;C1608X7R682KGT;GRM188R71H682KA01D;223858615634;C1608X7R1H682KT000N | Multiple |  | Purchase | SMT | 2 | PCS | PC194 PC214 |
| 2 | 55.B0710.S11G | 79.47719.2BL | CHIP CAP 470UF 2V EEFSX0D471X | R2_SA;HF_SA;G_SA; | Released | PANASONIC | EEFSX0D471XE | Single |  | Purchase | SMT | 4 | PCS | PTC4 PTC5 PTC6 PTC7 |
| 2 | 55.B0710.S11G | 82.20013.291 | OSC 48MHZ 50PPM 15PF 3.3V HSO321S SMD | R2_SA; | Released | HARMONY | SSW048000I3CH | Single |  | Purchase | SMT | 1 | PCS | OSC1 |
| 2 | 55.B0710.S11G | 82.20043.111 | OSC 50MHZ 50PPM DSO751SV SMD | R2_SA; | Released | KDS | 1XSH050000AVK | Single |  | Purchase | SMT | 1 | PCS | X1 |
| 2 | 55.B0710.S11G | 82.30001.931 | XTAL 32.768KHZ 8P20PPM DST310S | R2_SA; | Released | KDS | 1TJF080DP1A000A | Single |  | Purchase | SMT | 1 | PCS | X2 |
| 2 | 55.B0710.S11G | 82.30004.901 | XTAL 24MHZ 12PF20PPM HCX-3SB SMD | R2_SA;HF_SA; | Released | HOSONIC | E3SB24.0000F12M22 | Single |  | Purchase | SMT | 1 | PCS | X11 |
| 2 | 55.B0710.S11G | 82.30020.891 | XTAL 25MHZ 12P30PPM HSX531S | R2_SA; | Released | HARMONY | X1H025000FC1H | Single |  | Purchase | SMT | 2 | PCS | SX1 SX2 |
| 2 | 55.B0710.S11G | 83.01221.I70 | LED BLUE 12-21/BHC-YLMRY-2C | R2_SA;HF_SA; | Released | EVERLIGHT | 12-21/BHC-YLMRY/2C | Single |  | Purchase | SMT | 1 | PCS | LED5 |
| 2 | 55.B0710.S11G | 83.01521.H70 | LED RED 15-21-SURC-S530-A3-TR8 | R2_SA; | Released | EVERLIGHT | 15-21-SURC-S530-A3-TR8 | Single |  | Purchase | SMT | 1 | PCS | LED6 |
| 2 | 55.B0710.S11G | 83.01921.C70 | LED 1.6*0.8 YEL 19-21UYOC/S530 | R2_SA;HF_SA;G_SA; | Released | EVERLIGHT | 19-21UYOC/S530-A2TR8 | Single |  | Purchase | SMT | 2 | PCS | LED14 LED15 |
| 2 | 55.B0710.S11G | 83.01921.S70 | LED Y/G 19-21/G6C-BM2P1B/3T SM | R2_SA;HF_SA;G_SA; | Released | EVERLIGHT | 19-21/G6C-BM2P1B/3T | Single |  | Purchase | SMT | 4 | PCS | SLED25 SLED26 SLED27 SLED28 |
| 2 | 55.B0710.S11G | 83.1221R.070 | LED RED ET 12-21/R6C-AP1Q2L/2C SMD | R2_SA; | Released | EVERLIGHT | 12-21/R6C-AP1Q2L/2C | Single |  | Purchase | SMT | 1 | PCS | LED4 |
| 2 | 55.B0710.S11G | 83.SMF15.0AH | DIODE TVS SMF15A SOD-123FL | R2_SA; | Released | PANJIT | SMF15A | Single |  | Purchase | SMT | 1 | PCS | D37 |
| 2 | 55.B0710.S11G | 84.00359.C31 | FET MOS FDN359BN NC SUPERSOT23 | R2_SA; | Released | FAIRCHILD | FDN359BN | Single |  | Purchase | SMT | 2 | PCS | PQ3 Q78 |
| 2 | 55.B0710.S11G | 84.00925.03N | FET MOS PH0925CL NC LFPAK | R2_SA; | Released | NXP | PH0925CL | Single |  | Purchase | SMT | 2 | PCS | Q23 Q76 |
| 2 | 55.B0710.S11G | 84.03400.B37 | FET MOS AO3400A NC SOT-23 3P | R2_SA;HF_SA;G_SA; | Released | AOS | AO3400A | Single |  | Purchase | SMT | 3 | PCS | SQ1 SQ2 SQ5 |
| 2 | 55.B0710.S11G | 84.03904.L06 | XTOR PMBS3904 NPN SOT23 (GP) | R2_SA;HF_SA;G_SA; | Released | NXP | PMBS3904 | Single |  | Purchase | SMT | 2 | PCS | Q22 Q5 |
| 2 | 55.B0710.S11G | 84.04406.B37 | FET MOS AO4406AL NC SO-8(HF) | R2_SA;HF_SA;G_SA; | Released | AOS | AO4406AL | Single |  | Purchase | SMT | 1 | PCS | PQ1 |
| 2 | 55.B0710.S11G | 84.27002.C3F | FET MOS 2N7002DW-7-F NC SOT363 | R2_SA;HF_SA; | Released | DIODES | 2N7002DW-7-F | Single |  | Purchase | SMT | 3 | PCS | PU9 Q10 SU63 |
| 2 | 55.B0710.S11G | 84.2N702.E31 | FET MOS 2N7002A-7 NC SOT-23 ESD 1.2KV | R2_SA;HF_SA;G_SA; | Released | DIODES | 2N7002A-7 | Single |  | Purchase | SMT | 32 | PCS | PQ4 PQ5 PQ6 PQ7 Q11 Q12 Q13 Q14 Q15 Q16 Q17 Q19 Q20 Q21 Q6 Q7 Q8 Q9 Q92 Q93 Q94 Q97 SQ11 SQ12 SQ13 SQ14 SQ15 SQ16 SQ17 SQ18 SQ3 SQ4 |
| 2 | 55.B0710.S11G | 84.M3904.01K | XTOR MMBT3904TT1G NPN SOT-416 | R2_SA; | Released | ON | MMBT3904TT1G | Single |  | Purchase | SMT | 2 | PCS | Q77 Q80 |
| 2 | 55.B0710.S11G | 84.N3904.011 | XTOR NST3904F3T5G NPN SOT-1123 | R2_SA; | Released | ON | NST3904F3T5G | Single |  | Purchase | SMT | 1 | PCS | PQ33 |
| 1 | 55.B0710.D11G | 60.B0711.001 | ASSY PANTHER DUIDE RIGHT HB | R2_C; | Released | TBD |  | Single | E | Purchase | DIP | 1 | PCS |  |
| 1 | 55.B0710.D11G | 60.B0712.001 | ASSY PANTHER DUIDE LEFT HB | R2_C; | Released | TBD |  | Single | E | Purchase | DIP | 1 | PCS |  |
| 1 | 55.B0710.D11G | 60.B0725.001 | ASSY BASE BOARD RIGHT HANDLE HB PVT | R2_C; | Released | TBD |  | Single | E | Purchase | DIP | 1 | PCS |  |
| 1 | 55.B0710.D11G | 60.B0726.001 | ASSY BASE BOARD LEFT HANDLE HB PVT | R2_C; | Released | TBD |  | Single | E | Purchase | DIP | 1 | PCS |  |
| 1 | 55.B0710.D11G | 60.B0727.001 | ASSY BASE BOARD MYLAR HB PVT | R2_C; | Released | TBD |  | Single | E | Purchase | DIP | 1 | PCS |  |
| 1 | 55.B0710.D11G | 72.25635.A01 | IC FEROM MX25L25635FMI-10G SOP 16P | R2_SA; | Released | MXIC | MX25L25635FMI-10G | Single |  | Purchase | DIP | 1 | PCS | U19 |
| 1 | 55.B0710.D11G | 86.00T32.544 | SCRW WAFRE M3.0 L4 NYLOK | R2_SA; | Released | TBD |  | Single |  | Purchase | DIP | 8 | PCS |  |
| 1 | 55.B0710.D11G | 86.0A233.5R0 | SCRW PH FM +N 2.5x5-B | R2_SA; | Released | TBD |  | Single |  | Purchase | DIP | 2 | PCS |  |
| 1 | 55.B0710.D11G | 86.1A522.5R0 | SCREW M2-5 | R2_SA;G_SA; | Released | TBD | TBD | Single |  | Purchase | DIP | 4 | PCS |  |
| 1 | 55.B0710.D11G | 86.5A534.5R0 | SCRW FLAT M3 *5 | R2_SA;HF_SA; | Released | WEN HAOU |  | Single |  | Purchase | DIP | 5 | PCS |  |
